FILE_TYPE = MACRO_DRAWING;
SET COLOR_WIRE YELLOW;
SET COLOR_PROP ORANGE;
SET COLOR_DOT WHITE;
SET COLOR_ARC YELLOW;
SET COLOR_BODY GREEN;
SET COLOR_NOTE PURPLE;
SET PROP_DISPLAY VALUE;
SET PAGE_NUMBER P112;
FORCEADD 9ZXL0451EKILFT..1
(-3200 4850);
FORCEPROP 1 LAST LOCATION U72
J 0
(-3666 5865);
DISPLAY 0.489362 (-3666 5865);
PAINT SKYBLUE (-3666 5865);
FORCEPROP 0 LAST $SEC 1
J 0
(-3600 6275);
DISPLAY 0.680851 (-3600 6275);
PAINT MONO (-3600 6275);
DISPLAY INVISIBLE (-3600 6275);
FORCEPROP 0 LAST CDS_SEC 1
J 0
(-3600 6275);
DISPLAY 1.021277 (-3600 6275);
DISPLAY INVISIBLE (-3600 6275);
FORCEPROP 0 LASTPIN (-3825 4625) $PN 1
J 2
(-3835 4635);
DISPLAY 0.489362 (-3835 4635);
PAINT MONO (-3835 4635);
FORCEPROP 0 LASTPIN (-2575 5325) $PN 32
J 0
(-2565 5335);
DISPLAY 0.489362 (-2565 5335);
PAINT MONO (-2565 5335);
FORCEPROP 0 LASTPIN (-2575 5125) $PN 13
J 0
(-2565 5135);
DISPLAY 0.489362 (-2565 5135);
PAINT MONO (-2565 5135);
FORCEPROP 0 LASTPIN (-2575 5075) $PN 14
J 0
(-2565 5085);
DISPLAY 0.489362 (-2565 5085);
PAINT MONO (-2565 5085);
FORCEPROP 0 LASTPIN (-2575 5025) $PN 19
J 0
(-2565 5035);
DISPLAY 0.489362 (-2565 5035);
PAINT MONO (-2565 5035);
FORCEPROP 0 LASTPIN (-2575 4975) $PN 20
J 0
(-2565 4985);
DISPLAY 0.489362 (-2565 4985);
PAINT MONO (-2565 4985);
FORCEPROP 0 LASTPIN (-2575 4925) $PN 22
J 0
(-2565 4935);
DISPLAY 0.489362 (-2565 4935);
PAINT MONO (-2565 4935);
FORCEPROP 0 LASTPIN (-2575 4875) $PN 23
J 0
(-2565 4885);
DISPLAY 0.489362 (-2565 4885);
PAINT MONO (-2565 4885);
FORCEPROP 0 LASTPIN (-2575 4825) $PN 27
J 0
(-2565 4835);
DISPLAY 0.489362 (-2565 4835);
PAINT MONO (-2565 4835);
FORCEPROP 0 LASTPIN (-2575 4775) $PN 28
J 0
(-2565 4785);
DISPLAY 0.489362 (-2565 4785);
PAINT MONO (-2565 4785);
FORCEPROP 0 LASTPIN (-3825 5025) $PN 3
J 2
(-3835 5035);
DISPLAY 0.489362 (-3835 5035);
PAINT MONO (-3835 5035);
FORCEPROP 0 LASTPIN (-3825 4975) $PN 4
J 2
(-3835 4985);
DISPLAY 0.489362 (-3835 4985);
PAINT MONO (-3835 4985);
FORCEPROP 0 LASTPIN (-2575 4225) $PN 33
J 0
(-2565 4235);
DISPLAY 0.489362 (-2565 4235);
PAINT MONO (-2565 4235);
FORCEPROP 0 LASTPIN (-3825 4575) $PN 9
J 2
(-3835 4585);
DISPLAY 0.489362 (-3835 4585);
PAINT MONO (-3835 4585);
FORCEPROP 0 LASTPIN (-3825 4525) $PN 8
J 2
(-3835 4535);
DISPLAY 0.489362 (-3835 4535);
PAINT MONO (-3835 4535);
FORCEPROP 0 LASTPIN (-3825 4375) $PN 10
J 2
(-3835 4385);
DISPLAY 0.489362 (-3835 4385);
PAINT MONO (-3835 4385);
FORCEPROP 0 LASTPIN (-3825 4325) $PN 11
J 2
(-3835 4335);
DISPLAY 0.489362 (-3835 4335);
PAINT MONO (-3835 4335);
FORCEPROP 0 LASTPIN (-3825 4275) $PN 17
J 2
(-3835 4285);
DISPLAY 0.489362 (-3835 4285);
PAINT MONO (-3835 4285);
FORCEPROP 0 LASTPIN (-3825 4225) $PN 30
J 2
(-3835 4235);
DISPLAY 0.489362 (-3835 4235);
PAINT MONO (-3835 4235);
FORCEPROP 0 LASTPIN (-3825 4725) $PN 7
J 2
(-3835 4735);
DISPLAY 0.489362 (-3835 4735);
PAINT MONO (-3835 4735);
FORCEPROP 0 LASTPIN (-3825 4775) $PN 6
J 2
(-3835 4785);
DISPLAY 0.489362 (-3835 4785);
PAINT MONO (-3835 4785);
FORCEPROP 0 LASTPIN (-3825 5475) $PN 12
J 2
(-3835 5485);
DISPLAY 0.489362 (-3835 5485);
PAINT MONO (-3835 5485);
FORCEPROP 0 LASTPIN (-3825 5425) $PN 16
J 2
(-3835 5435);
DISPLAY 0.489362 (-3835 5435);
PAINT MONO (-3835 5435);
FORCEPROP 0 LASTPIN (-3825 5375) $PN 21
J 2
(-3835 5385);
DISPLAY 0.489362 (-3835 5385);
PAINT MONO (-3835 5385);
FORCEPROP 0 LASTPIN (-3825 5325) $PN 25
J 2
(-3835 5335);
DISPLAY 0.489362 (-3835 5335);
PAINT MONO (-3835 5335);
FORCEPROP 0 LASTPIN (-3825 5275) $PN 29
J 2
(-3835 5285);
DISPLAY 0.489362 (-3835 5285);
PAINT MONO (-3835 5285);
FORCEPROP 0 LASTPIN (-2575 5475) $PN 31
J 0
(-2565 5485);
DISPLAY 0.489362 (-2565 5485);
PAINT MONO (-2565 5485);
FORCEPROP 0 LASTPIN (-3825 5175) $PN 2
J 2
(-3835 5185);
DISPLAY 0.489362 (-3835 5185);
PAINT MONO (-3835 5185);
FORCEPROP 0 LASTPIN (-2575 4575) $PN 15
J 0
(-2565 4585);
DISPLAY 0.489362 (-2565 4585);
PAINT MONO (-2565 4585);
FORCEPROP 0 LASTPIN (-2575 4525) $PN 18
J 0
(-2565 4535);
DISPLAY 0.489362 (-2565 4535);
PAINT MONO (-2565 4535);
FORCEPROP 0 LASTPIN (-2575 4475) $PN 24
J 0
(-2565 4485);
DISPLAY 0.489362 (-2565 4485);
PAINT MONO (-2565 4485);
FORCEPROP 0 LASTPIN (-2575 4425) $PN 26
J 0
(-2565 4435);
DISPLAY 0.489362 (-2565 4435);
PAINT MONO (-2565 4435);
FORCEPROP 0 LASTPIN (-3825 4875) $PN 5
J 2
(-3835 4885);
DISPLAY 0.489362 (-3835 4885);
PAINT MONO (-3835 4885);
FORCEPROP 2 LAST PART_TYPE SMLF
J 0
(-3600 6225);
DISPLAY 1.021277 (-3600 6225);
FORCEPROP 1 LAST MATERIAL IC
J 0
(-3666 5591);
DISPLAY 0.489362 (-3666 5591);
PAINT SKYBLUE (-3666 5591);
FORCEPROP 2 LAST VALUE 9ZXL0451EKILFT
J 0
(-3600 6175);
DISPLAY 0.489362 (-3600 6175);
PAINT SKYBLUE (-3600 6175);
FORCEPROP 1 LAST PART_NUMBER AL000451003
J 0
(-3666 5718);
DISPLAY 0.489362 (-3666 5718);
PAINT SKYBLUE (-3666 5718);
FORCEPROP 1 LAST NEEDS_NO_SIZE TRUE
J 0
(-3200 4850);
DISPLAY 0.723404 (-3200 4850);
PAINT GREEN (-3200 4850);
DISPLAY INVISIBLE (-3200 4850);
FORCEPROP 2 LAST CDS_LIB pure_quanta
J 0
(-3200 4850);
DISPLAY INVISIBLE (-3200 4850);
FORCEPROP 1 LAST CDS_LMAN_SYM_OUTLINE -475,725,475,-725
J 0
(-3200 4850);
DISPLAY 0.468085 (-3200 4850);
PAINT GREEN (-3200 4850);
DISPLAY INVISIBLE (-3200 4850);
FORCEPROP 1 LAST PATH I1
J 0
(-3200 4850);
DISPLAY 0.723404 (-3200 4850);
PAINT GREEN (-3200 4850);
DISPLAY INVISIBLE (-3200 4850);
FORCEADD Q_RES..1
(-1525 5025);
FORCEPROP 1 LAST LOCATION R2306
J 0
(-1750 5025);
DISPLAY 0.489362 (-1750 5025);
PAINT SKYBLUE (-1750 5025);
FORCEPROP 0 LAST $SEC 1
J 0
(-1600 5075);
DISPLAY 0.680851 (-1600 5075);
PAINT MONO (-1600 5075);
DISPLAY INVISIBLE (-1600 5075);
FORCEPROP 0 LAST CDS_SEC 1
J 0
(-1600 5075);
DISPLAY 1.021277 (-1600 5075);
DISPLAY INVISIBLE (-1600 5075);
FORCEPROP 1 LASTPIN (-1625 5025) $PN 1
J 0
(-1613 5037);
DISPLAY 0.489362 (-1613 5037);
PAINT MONO (-1613 5037);
FORCEPROP 1 LASTPIN (-1425 5025) $PN 2
J 0
(-1463 5037);
DISPLAY 0.489362 (-1463 5037);
PAINT MONO (-1463 5037);
FORCEPROP 1 LAST VALUE 0
J 2
(-1400 5025);
DISPLAY 0.489362 (-1400 5025);
PAINT SKYBLUE (-1400 5025);
FORCEPROP 2 LAST CDS_LIB pure_quanta
J 0
(-1525 5025);
DISPLAY INVISIBLE (-1525 5025);
FORCEPROP 1 LAST PATH I100
J 0
(-1575 5175);
DISPLAY 0.978723 (-1575 5175);
PAINT WHITE (-1575 5175);
DISPLAY INVISIBLE (-1575 5175);
FORCEPROP 1 LAST WATTAGE 1/16W
J 2
(-1125 4950);
DISPLAY 0.489362 (-1125 4950);
PAINT SKYBLUE (-1125 4950);
DISPLAY INVISIBLE (-1125 4950);
FORCEPROP 1 LAST MATERIAL CHIP
J 0
(-1100 4950);
DISPLAY 0.489362 (-1100 4950);
PAINT SKYBLUE (-1100 4950);
DISPLAY INVISIBLE (-1100 4950);
FORCEPROP 1 LAST TOLERANCE 5%
J 0
(-1550 4950);
DISPLAY 0.489362 (-1550 4950);
PAINT SKYBLUE (-1550 4950);
DISPLAY INVISIBLE (-1550 4950);
FORCEPROP 1 LAST PART_NUMBER CS00002JB38
J 0
(-1500 5075);
DISPLAY 0.489362 (-1500 5075);
PAINT SKYBLUE (-1500 5075);
DISPLAY INVISIBLE (-1500 5075);
FORCEPROP 1 LAST PACK_TYPE 0402LF
J 0
(-1475 4950);
DISPLAY 0.489362 (-1475 4950);
PAINT SKYBLUE (-1475 4950);
DISPLAY INVISIBLE (-1475 4950);
FORCEADD Q_RES..1
(-1525 4975);
FORCEPROP 1 LAST LOCATION R2307
J 0
(-1750 4975);
DISPLAY 0.489362 (-1750 4975);
PAINT SKYBLUE (-1750 4975);
FORCEPROP 0 LAST $SEC 1
J 0
(-1600 5025);
DISPLAY 0.680851 (-1600 5025);
PAINT MONO (-1600 5025);
DISPLAY INVISIBLE (-1600 5025);
FORCEPROP 0 LAST CDS_SEC 1
J 0
(-1600 5025);
DISPLAY 1.021277 (-1600 5025);
DISPLAY INVISIBLE (-1600 5025);
FORCEPROP 1 LASTPIN (-1625 4975) $PN 1
J 0
(-1613 4987);
DISPLAY 0.489362 (-1613 4987);
PAINT MONO (-1613 4987);
FORCEPROP 1 LASTPIN (-1425 4975) $PN 2
J 0
(-1463 4987);
DISPLAY 0.489362 (-1463 4987);
PAINT MONO (-1463 4987);
FORCEPROP 1 LAST VALUE 0
J 2
(-1400 4975);
DISPLAY 0.489362 (-1400 4975);
PAINT SKYBLUE (-1400 4975);
FORCEPROP 2 LAST CDS_LIB pure_quanta
J 0
(-1525 4975);
DISPLAY INVISIBLE (-1525 4975);
FORCEPROP 1 LAST PATH I101
J 0
(-1575 5125);
DISPLAY 0.978723 (-1575 5125);
PAINT WHITE (-1575 5125);
DISPLAY INVISIBLE (-1575 5125);
FORCEPROP 1 LAST WATTAGE 1/16W
J 2
(-1125 4900);
DISPLAY 0.489362 (-1125 4900);
PAINT SKYBLUE (-1125 4900);
DISPLAY INVISIBLE (-1125 4900);
FORCEPROP 1 LAST MATERIAL CHIP
J 0
(-1100 4900);
DISPLAY 0.489362 (-1100 4900);
PAINT SKYBLUE (-1100 4900);
DISPLAY INVISIBLE (-1100 4900);
FORCEPROP 1 LAST TOLERANCE 5%
J 0
(-1550 4900);
DISPLAY 0.489362 (-1550 4900);
PAINT SKYBLUE (-1550 4900);
DISPLAY INVISIBLE (-1550 4900);
FORCEPROP 1 LAST PART_NUMBER CS00002JB38
J 0
(-1500 5025);
DISPLAY 0.489362 (-1500 5025);
PAINT SKYBLUE (-1500 5025);
DISPLAY INVISIBLE (-1500 5025);
FORCEPROP 1 LAST PACK_TYPE 0402LF
J 0
(-1475 4900);
DISPLAY 0.489362 (-1475 4900);
PAINT SKYBLUE (-1475 4900);
DISPLAY INVISIBLE (-1475 4900);
FORCEADD Q_RES..1
(-1525 4925);
FORCEPROP 1 LAST LOCATION R2308
J 0
(-1750 4925);
DISPLAY 0.489362 (-1750 4925);
PAINT SKYBLUE (-1750 4925);
FORCEPROP 0 LAST $SEC 1
J 0
(-1600 4975);
DISPLAY 0.680851 (-1600 4975);
PAINT MONO (-1600 4975);
DISPLAY INVISIBLE (-1600 4975);
FORCEPROP 0 LAST CDS_SEC 1
J 0
(-1600 4975);
DISPLAY 1.021277 (-1600 4975);
DISPLAY INVISIBLE (-1600 4975);
FORCEPROP 1 LASTPIN (-1625 4925) $PN 1
J 0
(-1613 4937);
DISPLAY 0.489362 (-1613 4937);
PAINT MONO (-1613 4937);
FORCEPROP 1 LASTPIN (-1425 4925) $PN 2
J 0
(-1463 4937);
DISPLAY 0.489362 (-1463 4937);
PAINT MONO (-1463 4937);
FORCEPROP 1 LAST VALUE 0
J 2
(-1400 4925);
DISPLAY 0.489362 (-1400 4925);
PAINT SKYBLUE (-1400 4925);
FORCEPROP 2 LAST CDS_LIB pure_quanta
J 0
(-1525 4925);
DISPLAY INVISIBLE (-1525 4925);
FORCEPROP 1 LAST PATH I102
J 0
(-1575 5075);
DISPLAY 0.978723 (-1575 5075);
PAINT WHITE (-1575 5075);
DISPLAY INVISIBLE (-1575 5075);
FORCEPROP 1 LAST WATTAGE 1/16W
J 2
(-1125 4850);
DISPLAY 0.489362 (-1125 4850);
PAINT SKYBLUE (-1125 4850);
DISPLAY INVISIBLE (-1125 4850);
FORCEPROP 1 LAST MATERIAL CHIP
J 0
(-1100 4850);
DISPLAY 0.489362 (-1100 4850);
PAINT SKYBLUE (-1100 4850);
DISPLAY INVISIBLE (-1100 4850);
FORCEPROP 1 LAST TOLERANCE 5%
J 0
(-1550 4850);
DISPLAY 0.489362 (-1550 4850);
PAINT SKYBLUE (-1550 4850);
DISPLAY INVISIBLE (-1550 4850);
FORCEPROP 1 LAST PART_NUMBER CS00002JB38
J 0
(-1500 4975);
DISPLAY 0.489362 (-1500 4975);
PAINT SKYBLUE (-1500 4975);
DISPLAY INVISIBLE (-1500 4975);
FORCEPROP 1 LAST PACK_TYPE 0402LF
J 0
(-1475 4850);
DISPLAY 0.489362 (-1475 4850);
PAINT SKYBLUE (-1475 4850);
DISPLAY INVISIBLE (-1475 4850);
FORCEADD Q_RES..1
(-1525 4875);
FORCEPROP 1 LAST LOCATION R2309
J 0
(-1750 4875);
DISPLAY 0.489362 (-1750 4875);
PAINT SKYBLUE (-1750 4875);
FORCEPROP 0 LAST $SEC 1
J 0
(-1600 4925);
DISPLAY 0.680851 (-1600 4925);
PAINT MONO (-1600 4925);
DISPLAY INVISIBLE (-1600 4925);
FORCEPROP 0 LAST CDS_SEC 1
J 0
(-1600 4925);
DISPLAY 1.021277 (-1600 4925);
DISPLAY INVISIBLE (-1600 4925);
FORCEPROP 1 LASTPIN (-1625 4875) $PN 1
J 0
(-1613 4887);
DISPLAY 0.489362 (-1613 4887);
PAINT MONO (-1613 4887);
FORCEPROP 1 LASTPIN (-1425 4875) $PN 2
J 0
(-1463 4887);
DISPLAY 0.489362 (-1463 4887);
PAINT MONO (-1463 4887);
FORCEPROP 1 LAST VALUE 0
J 2
(-1400 4875);
DISPLAY 0.489362 (-1400 4875);
PAINT SKYBLUE (-1400 4875);
FORCEPROP 2 LAST CDS_LIB pure_quanta
J 0
(-1525 4875);
DISPLAY INVISIBLE (-1525 4875);
FORCEPROP 1 LAST PATH I103
J 0
(-1575 5025);
DISPLAY 0.978723 (-1575 5025);
PAINT WHITE (-1575 5025);
DISPLAY INVISIBLE (-1575 5025);
FORCEPROP 1 LAST WATTAGE 1/16W
J 2
(-1125 4800);
DISPLAY 0.489362 (-1125 4800);
PAINT SKYBLUE (-1125 4800);
DISPLAY INVISIBLE (-1125 4800);
FORCEPROP 1 LAST MATERIAL CHIP
J 0
(-1100 4800);
DISPLAY 0.489362 (-1100 4800);
PAINT SKYBLUE (-1100 4800);
DISPLAY INVISIBLE (-1100 4800);
FORCEPROP 1 LAST TOLERANCE 5%
J 0
(-1550 4800);
DISPLAY 0.489362 (-1550 4800);
PAINT SKYBLUE (-1550 4800);
DISPLAY INVISIBLE (-1550 4800);
FORCEPROP 1 LAST PART_NUMBER CS00002JB38
J 0
(-1500 4925);
DISPLAY 0.489362 (-1500 4925);
PAINT SKYBLUE (-1500 4925);
DISPLAY INVISIBLE (-1500 4925);
FORCEPROP 1 LAST PACK_TYPE 0402LF
J 0
(-1475 4800);
DISPLAY 0.489362 (-1475 4800);
PAINT SKYBLUE (-1475 4800);
DISPLAY INVISIBLE (-1475 4800);
FORCEADD Q_RES..1
(-1525 5125);
FORCEPROP 1 LAST LOCATION R2304
J 0
(-1750 5125);
DISPLAY 0.489362 (-1750 5125);
PAINT SKYBLUE (-1750 5125);
FORCEPROP 0 LAST $SEC 1
J 0
(-1600 5175);
DISPLAY 0.680851 (-1600 5175);
PAINT MONO (-1600 5175);
DISPLAY INVISIBLE (-1600 5175);
FORCEPROP 0 LAST CDS_SEC 1
J 0
(-1600 5175);
DISPLAY 1.021277 (-1600 5175);
DISPLAY INVISIBLE (-1600 5175);
FORCEPROP 1 LASTPIN (-1625 5125) $PN 1
J 0
(-1613 5137);
DISPLAY 0.489362 (-1613 5137);
PAINT MONO (-1613 5137);
FORCEPROP 1 LASTPIN (-1425 5125) $PN 2
J 0
(-1463 5137);
DISPLAY 0.489362 (-1463 5137);
PAINT MONO (-1463 5137);
FORCEPROP 1 LAST VALUE 0
J 2
(-1400 5125);
DISPLAY 0.489362 (-1400 5125);
PAINT SKYBLUE (-1400 5125);
FORCEPROP 2 LAST CDS_LIB pure_quanta
J 0
(-1525 5125);
DISPLAY INVISIBLE (-1525 5125);
FORCEPROP 1 LAST PATH I104
J 0
(-1575 5275);
DISPLAY 0.978723 (-1575 5275);
PAINT WHITE (-1575 5275);
DISPLAY INVISIBLE (-1575 5275);
FORCEPROP 1 LAST WATTAGE 1/16W
J 2
(-1125 5050);
DISPLAY 0.489362 (-1125 5050);
PAINT SKYBLUE (-1125 5050);
DISPLAY INVISIBLE (-1125 5050);
FORCEPROP 1 LAST MATERIAL CHIP
J 0
(-1100 5050);
DISPLAY 0.489362 (-1100 5050);
PAINT SKYBLUE (-1100 5050);
DISPLAY INVISIBLE (-1100 5050);
FORCEPROP 1 LAST TOLERANCE 5%
J 0
(-1550 5050);
DISPLAY 0.489362 (-1550 5050);
PAINT SKYBLUE (-1550 5050);
DISPLAY INVISIBLE (-1550 5050);
FORCEPROP 1 LAST PART_NUMBER CS00002JB38
J 0
(-1500 5175);
DISPLAY 0.489362 (-1500 5175);
PAINT SKYBLUE (-1500 5175);
DISPLAY INVISIBLE (-1500 5175);
FORCEPROP 1 LAST PACK_TYPE 0402LF
J 0
(-1475 5050);
DISPLAY 0.489362 (-1475 5050);
PAINT SKYBLUE (-1475 5050);
DISPLAY INVISIBLE (-1475 5050);
FORCEADD Q_RES..1
(-1425 2075);
FORCEPROP 1 LAST LOCATION R2301
J 0
(-1625 2075);
DISPLAY 0.489362 (-1625 2075);
PAINT SKYBLUE (-1625 2075);
FORCEPROP 0 LAST $SEC 1
J 0
(-1500 2125);
DISPLAY 0.680851 (-1500 2125);
PAINT MONO (-1500 2125);
DISPLAY INVISIBLE (-1500 2125);
FORCEPROP 0 LAST CDS_SEC 1
J 0
(-1500 2125);
DISPLAY 1.021277 (-1500 2125);
DISPLAY INVISIBLE (-1500 2125);
FORCEPROP 1 LASTPIN (-1525 2075) $PN 1
J 0
(-1513 2087);
DISPLAY 0.489362 (-1513 2087);
PAINT MONO (-1513 2087);
FORCEPROP 1 LASTPIN (-1325 2075) $PN 2
J 0
(-1363 2087);
DISPLAY 0.489362 (-1363 2087);
PAINT MONO (-1363 2087);
FORCEPROP 1 LAST VALUE 0
J 2
(-1300 2075);
DISPLAY 0.489362 (-1300 2075);
PAINT SKYBLUE (-1300 2075);
FORCEPROP 2 LAST CDS_LIB pure_quanta
J 0
(-1425 2075);
DISPLAY INVISIBLE (-1425 2075);
FORCEPROP 1 LAST PATH I105
J 0
(-1475 2225);
DISPLAY 0.978723 (-1475 2225);
PAINT WHITE (-1475 2225);
DISPLAY INVISIBLE (-1475 2225);
FORCEPROP 1 LAST WATTAGE 1/16W
J 2
(-1025 2000);
DISPLAY 0.489362 (-1025 2000);
PAINT SKYBLUE (-1025 2000);
DISPLAY INVISIBLE (-1025 2000);
FORCEPROP 1 LAST MATERIAL CHIP
J 0
(-1000 2000);
DISPLAY 0.489362 (-1000 2000);
PAINT SKYBLUE (-1000 2000);
DISPLAY INVISIBLE (-1000 2000);
FORCEPROP 1 LAST TOLERANCE 5%
J 0
(-1450 2000);
DISPLAY 0.489362 (-1450 2000);
PAINT SKYBLUE (-1450 2000);
DISPLAY INVISIBLE (-1450 2000);
FORCEPROP 1 LAST PART_NUMBER CS00002JB38
J 0
(-1400 2125);
DISPLAY 0.489362 (-1400 2125);
PAINT SKYBLUE (-1400 2125);
DISPLAY INVISIBLE (-1400 2125);
FORCEPROP 1 LAST PACK_TYPE 0402LF
J 0
(-1375 2000);
DISPLAY 0.489362 (-1375 2000);
PAINT SKYBLUE (-1375 2000);
DISPLAY INVISIBLE (-1375 2000);
FORCEADD Q_RES..1
(-1425 2025);
FORCEPROP 1 LAST LOCATION R2302
J 0
(-1625 2025);
DISPLAY 0.489362 (-1625 2025);
PAINT SKYBLUE (-1625 2025);
FORCEPROP 0 LAST $SEC 1
J 0
(-1500 2075);
DISPLAY 0.680851 (-1500 2075);
PAINT MONO (-1500 2075);
DISPLAY INVISIBLE (-1500 2075);
FORCEPROP 0 LAST CDS_SEC 1
J 0
(-1500 2075);
DISPLAY 1.021277 (-1500 2075);
DISPLAY INVISIBLE (-1500 2075);
FORCEPROP 1 LASTPIN (-1525 2025) $PN 1
J 0
(-1513 2037);
DISPLAY 0.489362 (-1513 2037);
PAINT MONO (-1513 2037);
FORCEPROP 1 LASTPIN (-1325 2025) $PN 2
J 0
(-1363 2037);
DISPLAY 0.489362 (-1363 2037);
PAINT MONO (-1363 2037);
FORCEPROP 1 LAST VALUE 0
J 2
(-1300 2025);
DISPLAY 0.489362 (-1300 2025);
PAINT SKYBLUE (-1300 2025);
FORCEPROP 2 LAST CDS_LIB pure_quanta
J 0
(-1425 2025);
DISPLAY INVISIBLE (-1425 2025);
FORCEPROP 1 LAST PATH I106
J 0
(-1475 2175);
DISPLAY 0.978723 (-1475 2175);
PAINT WHITE (-1475 2175);
DISPLAY INVISIBLE (-1475 2175);
FORCEPROP 1 LAST WATTAGE 1/16W
J 2
(-1025 1950);
DISPLAY 0.489362 (-1025 1950);
PAINT SKYBLUE (-1025 1950);
DISPLAY INVISIBLE (-1025 1950);
FORCEPROP 1 LAST MATERIAL CHIP
J 0
(-1000 1950);
DISPLAY 0.489362 (-1000 1950);
PAINT SKYBLUE (-1000 1950);
DISPLAY INVISIBLE (-1000 1950);
FORCEPROP 1 LAST TOLERANCE 5%
J 0
(-1450 1950);
DISPLAY 0.489362 (-1450 1950);
PAINT SKYBLUE (-1450 1950);
DISPLAY INVISIBLE (-1450 1950);
FORCEPROP 1 LAST PART_NUMBER CS00002JB38
J 0
(-1400 2075);
DISPLAY 0.489362 (-1400 2075);
PAINT SKYBLUE (-1400 2075);
DISPLAY INVISIBLE (-1400 2075);
FORCEPROP 1 LAST PACK_TYPE 0402LF
J 0
(-1375 1950);
DISPLAY 0.489362 (-1375 1950);
PAINT SKYBLUE (-1375 1950);
DISPLAY INVISIBLE (-1375 1950);
FORCEADD Q_RES..1
(-1425 1975);
FORCEPROP 1 LAST LOCATION R2303
J 0
(-1625 1975);
DISPLAY 0.489362 (-1625 1975);
PAINT SKYBLUE (-1625 1975);
FORCEPROP 0 LAST $SEC 1
J 0
(-1500 2025);
DISPLAY 0.680851 (-1500 2025);
PAINT MONO (-1500 2025);
DISPLAY INVISIBLE (-1500 2025);
FORCEPROP 0 LAST CDS_SEC 1
J 0
(-1500 2025);
DISPLAY 1.021277 (-1500 2025);
DISPLAY INVISIBLE (-1500 2025);
FORCEPROP 1 LASTPIN (-1525 1975) $PN 1
J 0
(-1513 1987);
DISPLAY 0.489362 (-1513 1987);
PAINT MONO (-1513 1987);
FORCEPROP 1 LASTPIN (-1325 1975) $PN 2
J 0
(-1363 1987);
DISPLAY 0.489362 (-1363 1987);
PAINT MONO (-1363 1987);
FORCEPROP 1 LAST VALUE 0
J 2
(-1300 1975);
DISPLAY 0.489362 (-1300 1975);
PAINT SKYBLUE (-1300 1975);
FORCEPROP 2 LAST CDS_LIB pure_quanta
J 0
(-1425 1975);
DISPLAY INVISIBLE (-1425 1975);
FORCEPROP 1 LAST PATH I107
J 0
(-1475 2125);
DISPLAY 0.978723 (-1475 2125);
PAINT WHITE (-1475 2125);
DISPLAY INVISIBLE (-1475 2125);
FORCEPROP 1 LAST WATTAGE 1/16W
J 2
(-1025 1900);
DISPLAY 0.489362 (-1025 1900);
PAINT SKYBLUE (-1025 1900);
DISPLAY INVISIBLE (-1025 1900);
FORCEPROP 1 LAST MATERIAL CHIP
J 0
(-1000 1900);
DISPLAY 0.489362 (-1000 1900);
PAINT SKYBLUE (-1000 1900);
DISPLAY INVISIBLE (-1000 1900);
FORCEPROP 1 LAST TOLERANCE 5%
J 0
(-1450 1900);
DISPLAY 0.489362 (-1450 1900);
PAINT SKYBLUE (-1450 1900);
DISPLAY INVISIBLE (-1450 1900);
FORCEPROP 1 LAST PART_NUMBER CS00002JB38
J 0
(-1400 2025);
DISPLAY 0.489362 (-1400 2025);
PAINT SKYBLUE (-1400 2025);
DISPLAY INVISIBLE (-1400 2025);
FORCEPROP 1 LAST PACK_TYPE 0402LF
J 0
(-1375 1900);
DISPLAY 0.489362 (-1375 1900);
PAINT SKYBLUE (-1375 1900);
DISPLAY INVISIBLE (-1375 1900);
FORCEADD Q_RES..1
(-1425 2125);
FORCEPROP 1 LAST LOCATION R2300
J 0
(-1625 2125);
DISPLAY 0.489362 (-1625 2125);
PAINT SKYBLUE (-1625 2125);
FORCEPROP 0 LAST $SEC 1
J 0
(-1500 2175);
DISPLAY 0.680851 (-1500 2175);
PAINT MONO (-1500 2175);
DISPLAY INVISIBLE (-1500 2175);
FORCEPROP 0 LAST CDS_SEC 1
J 0
(-1500 2175);
DISPLAY 1.021277 (-1500 2175);
DISPLAY INVISIBLE (-1500 2175);
FORCEPROP 1 LASTPIN (-1525 2125) $PN 1
J 0
(-1513 2137);
DISPLAY 0.489362 (-1513 2137);
PAINT MONO (-1513 2137);
FORCEPROP 1 LASTPIN (-1325 2125) $PN 2
J 0
(-1363 2137);
DISPLAY 0.489362 (-1363 2137);
PAINT MONO (-1363 2137);
FORCEPROP 1 LAST VALUE 0
J 2
(-1300 2125);
DISPLAY 0.489362 (-1300 2125);
PAINT SKYBLUE (-1300 2125);
FORCEPROP 2 LAST CDS_LIB pure_quanta
J 0
(-1425 2125);
DISPLAY INVISIBLE (-1425 2125);
FORCEPROP 1 LAST PATH I110
J 0
(-1475 2275);
DISPLAY 0.978723 (-1475 2275);
PAINT WHITE (-1475 2275);
DISPLAY INVISIBLE (-1475 2275);
FORCEPROP 1 LAST WATTAGE 1/16W
J 2
(-1025 2050);
DISPLAY 0.489362 (-1025 2050);
PAINT SKYBLUE (-1025 2050);
DISPLAY INVISIBLE (-1025 2050);
FORCEPROP 1 LAST MATERIAL CHIP
J 0
(-1000 2050);
DISPLAY 0.489362 (-1000 2050);
PAINT SKYBLUE (-1000 2050);
DISPLAY INVISIBLE (-1000 2050);
FORCEPROP 1 LAST TOLERANCE 5%
J 0
(-1450 2050);
DISPLAY 0.489362 (-1450 2050);
PAINT SKYBLUE (-1450 2050);
DISPLAY INVISIBLE (-1450 2050);
FORCEPROP 1 LAST PART_NUMBER CS00002JB38
J 0
(-1400 2175);
DISPLAY 0.489362 (-1400 2175);
PAINT SKYBLUE (-1400 2175);
DISPLAY INVISIBLE (-1400 2175);
FORCEPROP 1 LAST PACK_TYPE 0402LF
J 0
(-1375 2050);
DISPLAY 0.489362 (-1375 2050);
PAINT SKYBLUE (-1375 2050);
DISPLAY INVISIBLE (-1375 2050);
FORCEADD OFFPAGE..2
(-475 1975);
FORCEPROP 2 LAST $XR0 127 
J 0
(-286 1975);
DISPLAY 0.638298 (-286 1975);
PAINT MONO (-286 1975);
FORCEPROP 2 LAST CDS_LIB standard
J 0
(-475 1975);
DISPLAY INVISIBLE (-475 1975);
FORCEPROP 1 LAST OFFPAGE TRUE
J 0
(-150 1850);
DISPLAY 0.723404 (-150 1850);
PAINT GREEN (-150 1850);
DISPLAY INVISIBLE (-150 1850);
FORCEPROP 1 LAST COMMENT_BODY TRUE
J 0
(-520 1880);
DISPLAY 0.872340 (-520 1880);
PAINT GREEN (-520 1880);
DISPLAY INVISIBLE (-520 1880);
FORCEPROP 2 LAST PATH I111
J 0
(-275 2025);
DISPLAY 1.021277 (-275 2025);
DISPLAY INVISIBLE (-275 2025);
FORCEADD OFFPAGE..2
(-475 2025);
FORCEPROP 2 LAST $XR0 127 
J 0
(-286 2025);
DISPLAY 0.638298 (-286 2025);
PAINT MONO (-286 2025);
FORCEPROP 2 LAST CDS_LIB standard
J 0
(-475 2025);
DISPLAY INVISIBLE (-475 2025);
FORCEPROP 1 LAST OFFPAGE TRUE
J 0
(-150 1900);
DISPLAY 0.723404 (-150 1900);
PAINT GREEN (-150 1900);
DISPLAY INVISIBLE (-150 1900);
FORCEPROP 1 LAST COMMENT_BODY TRUE
J 0
(-520 1930);
DISPLAY 0.872340 (-520 1930);
PAINT GREEN (-520 1930);
DISPLAY INVISIBLE (-520 1930);
FORCEPROP 2 LAST PATH I112
J 0
(-275 2075);
DISPLAY 1.021277 (-275 2075);
DISPLAY INVISIBLE (-275 2075);
FORCEADD OFFPAGE..2
(-475 2075);
FORCEPROP 2 LAST $XR0 126 
J 0
(-286 2075);
DISPLAY 0.638298 (-286 2075);
PAINT MONO (-286 2075);
FORCEPROP 2 LAST CDS_LIB standard
J 0
(-475 2075);
DISPLAY INVISIBLE (-475 2075);
FORCEPROP 1 LAST OFFPAGE TRUE
J 0
(-150 1950);
DISPLAY 0.723404 (-150 1950);
PAINT GREEN (-150 1950);
DISPLAY INVISIBLE (-150 1950);
FORCEPROP 1 LAST COMMENT_BODY TRUE
J 0
(-520 1980);
DISPLAY 0.872340 (-520 1980);
PAINT GREEN (-520 1980);
DISPLAY INVISIBLE (-520 1980);
FORCEPROP 2 LAST PATH I113
J 0
(-275 2125);
DISPLAY 1.021277 (-275 2125);
DISPLAY INVISIBLE (-275 2125);
FORCEADD OFFPAGE..2
(-475 2125);
FORCEPROP 2 LAST $XR0 126 
J 0
(-286 2125);
DISPLAY 0.638298 (-286 2125);
PAINT MONO (-286 2125);
FORCEPROP 1 LAST COMMENT_BODY TRUE
J 0
(-520 2030);
DISPLAY 0.872340 (-520 2030);
PAINT GREEN (-520 2030);
DISPLAY INVISIBLE (-520 2030);
FORCEPROP 1 LAST OFFPAGE TRUE
J 0
(-150 2000);
DISPLAY 0.723404 (-150 2000);
PAINT GREEN (-150 2000);
DISPLAY INVISIBLE (-150 2000);
FORCEPROP 2 LAST PATH I114
J 0
(-275 2175);
DISPLAY 1.021277 (-275 2175);
DISPLAY INVISIBLE (-275 2175);
FORCEPROP 2 LAST CDS_LIB standard
J 0
(-475 2125);
DISPLAY INVISIBLE (-475 2125);
FORCEADD OFFPAGE..2
(-625 4875);
FORCEPROP 2 LAST $XR0 128 
J 0
(-436 4875);
DISPLAY 0.638298 (-436 4875);
PAINT MONO (-436 4875);
FORCEPROP 2 LAST PATH I115
J 0
(-425 4925);
DISPLAY 1.021277 (-425 4925);
DISPLAY INVISIBLE (-425 4925);
FORCEPROP 1 LAST OFFPAGE TRUE
J 0
(-300 4750);
DISPLAY 0.723404 (-300 4750);
PAINT GREEN (-300 4750);
DISPLAY INVISIBLE (-300 4750);
FORCEPROP 1 LAST COMMENT_BODY TRUE
J 0
(-670 4780);
DISPLAY 0.872340 (-670 4780);
PAINT GREEN (-670 4780);
DISPLAY INVISIBLE (-670 4780);
FORCEPROP 2 LAST CDS_LIB standard
J 0
(-625 4875);
DISPLAY INVISIBLE (-625 4875);
FORCEADD OFFPAGE..2
(-625 5125);
FORCEPROP 2 LAST $XR0 124 
J 0
(-436 5125);
DISPLAY 0.638298 (-436 5125);
PAINT MONO (-436 5125);
FORCEPROP 2 LAST PATH I116
J 0
(-425 5175);
DISPLAY 1.021277 (-425 5175);
DISPLAY INVISIBLE (-425 5175);
FORCEPROP 2 LAST CDS_LIB standard
J 0
(-625 5125);
DISPLAY INVISIBLE (-625 5125);
FORCEPROP 1 LAST OFFPAGE TRUE
J 0
(-300 5000);
DISPLAY 0.723404 (-300 5000);
PAINT GREEN (-300 5000);
DISPLAY INVISIBLE (-300 5000);
FORCEPROP 1 LAST COMMENT_BODY TRUE
J 0
(-670 5030);
DISPLAY 0.872340 (-670 5030);
PAINT GREEN (-670 5030);
DISPLAY INVISIBLE (-670 5030);
FORCEADD OFFPAGE..2
(-625 5025);
FORCEPROP 2 LAST $XR0 125 
J 0
(-436 5025);
DISPLAY 0.638298 (-436 5025);
PAINT MONO (-436 5025);
FORCEPROP 2 LAST PATH I117
J 0
(-425 5075);
DISPLAY 1.021277 (-425 5075);
DISPLAY INVISIBLE (-425 5075);
FORCEPROP 1 LAST COMMENT_BODY TRUE
J 0
(-670 4930);
DISPLAY 0.872340 (-670 4930);
PAINT GREEN (-670 4930);
DISPLAY INVISIBLE (-670 4930);
FORCEPROP 1 LAST OFFPAGE TRUE
J 0
(-300 4900);
DISPLAY 0.723404 (-300 4900);
PAINT GREEN (-300 4900);
DISPLAY INVISIBLE (-300 4900);
FORCEPROP 2 LAST CDS_LIB standard
J 0
(-625 5025);
DISPLAY INVISIBLE (-625 5025);
FORCEADD OFFPAGE..2
(-625 5075);
FORCEPROP 2 LAST $XR0 124 
J 0
(-436 5075);
DISPLAY 0.638298 (-436 5075);
PAINT MONO (-436 5075);
FORCEPROP 2 LAST PATH I118
J 0
(-425 5125);
DISPLAY 1.021277 (-425 5125);
DISPLAY INVISIBLE (-425 5125);
FORCEPROP 2 LAST CDS_LIB standard
J 0
(-625 5075);
DISPLAY INVISIBLE (-625 5075);
FORCEPROP 1 LAST OFFPAGE TRUE
J 0
(-300 4950);
DISPLAY 0.723404 (-300 4950);
PAINT GREEN (-300 4950);
DISPLAY INVISIBLE (-300 4950);
FORCEPROP 1 LAST COMMENT_BODY TRUE
J 0
(-670 4980);
DISPLAY 0.872340 (-670 4980);
PAINT GREEN (-670 4980);
DISPLAY INVISIBLE (-670 4980);
FORCEADD OFFPAGE..2
(-625 4975);
FORCEPROP 2 LAST $XR0 125 
J 0
(-436 4975);
DISPLAY 0.638298 (-436 4975);
PAINT MONO (-436 4975);
FORCEPROP 2 LAST PATH I119
J 0
(-425 5025);
DISPLAY 1.021277 (-425 5025);
DISPLAY INVISIBLE (-425 5025);
FORCEPROP 1 LAST COMMENT_BODY TRUE
J 0
(-670 4880);
DISPLAY 0.872340 (-670 4880);
PAINT GREEN (-670 4880);
DISPLAY INVISIBLE (-670 4880);
FORCEPROP 1 LAST OFFPAGE TRUE
J 0
(-300 4850);
DISPLAY 0.723404 (-300 4850);
PAINT GREEN (-300 4850);
DISPLAY INVISIBLE (-300 4850);
FORCEPROP 2 LAST CDS_LIB standard
J 0
(-625 4975);
DISPLAY INVISIBLE (-625 4975);
FORCEADD OFFPAGE..2
(-625 4925);
FORCEPROP 2 LAST $XR0 128 
J 0
(-436 4925);
DISPLAY 0.638298 (-436 4925);
PAINT MONO (-436 4925);
FORCEPROP 2 LAST PATH I120
J 0
(-425 4975);
DISPLAY 1.021277 (-425 4975);
DISPLAY INVISIBLE (-425 4975);
FORCEPROP 1 LAST OFFPAGE TRUE
J 0
(-300 4800);
DISPLAY 0.723404 (-300 4800);
PAINT GREEN (-300 4800);
DISPLAY INVISIBLE (-300 4800);
FORCEPROP 1 LAST COMMENT_BODY TRUE
J 0
(-670 4830);
DISPLAY 0.872340 (-670 4830);
PAINT GREEN (-670 4830);
DISPLAY INVISIBLE (-670 4830);
FORCEPROP 2 LAST CDS_LIB standard
J 0
(-625 4925);
DISPLAY INVISIBLE (-625 4925);
FORCEADD UNIVERSAL_GND..1
(-8325 1275);
FORCEPROP 3 LASTPIN (-8325 1325) SIG_NAME GND\g
J 0
(-8315 1335);
DISPLAY 0.659574 (-8315 1335);
PAINT MONO (-8315 1335);
DISPLAY INVISIBLE (-8315 1335);
FORCEPROP 1 LAST HDL_POWER GND
J 1
(-8300 1200);
DISPLAY 0.489362 (-8300 1200);
PAINT GREEN (-8300 1200);
FORCEPROP 2 LAST CDS_LIB pure_quanta_power
J 0
(-8325 1275);
DISPLAY INVISIBLE (-8325 1275);
FORCEPROP 1 LAST PATH I121
J 0
(-8250 1275);
DISPLAY 0.872340 (-8250 1275);
PAINT AQUA (-8250 1275);
DISPLAY INVISIBLE (-8250 1275);
FORCEADD Q_CAP..1
(-8325 1560);
FORCEPROP 1 LAST LOCATION C67
J 0
(-8275 1660);
DISPLAY 0.489362 (-8275 1660);
PAINT SKYBLUE (-8275 1660);
FORCEPROP 0 LAST $SEC 1
J 0
(-8275 1725);
DISPLAY 0.680851 (-8275 1725);
PAINT MONO (-8275 1725);
DISPLAY INVISIBLE (-8275 1725);
FORCEPROP 0 LAST CDS_SEC 1
J 0
(-8275 1725);
DISPLAY 1.021277 (-8275 1725);
DISPLAY INVISIBLE (-8275 1725);
FORCEPROP 1 LASTPIN (-8325 1660) $PN 1
J 0
(-8315 1640);
DISPLAY 0.489362 (-8315 1640);
PAINT MONO (-8315 1640);
FORCEPROP 1 LASTPIN (-8325 1460) $PN 2
J 0
(-8315 1440);
DISPLAY 0.489362 (-8315 1440);
PAINT MONO (-8315 1440);
FORCEPROP 1 LAST MATERIAL X6S
J 0
(-8275 1460);
DISPLAY 0.489362 (-8275 1460);
PAINT SKYBLUE (-8275 1460);
FORCEPROP 1 LAST TOLERANCE 10%
J 0
(-8275 1510);
DISPLAY 0.489362 (-8275 1510);
PAINT SKYBLUE (-8275 1510);
FORCEPROP 1 LAST VALUE 1UF
J 0
(-8275 1610);
DISPLAY 0.489362 (-8275 1610);
PAINT SKYBLUE (-8275 1610);
FORCEPROP 1 LAST VOLTAGE 25V
J 0
(-8275 1560);
DISPLAY 0.489362 (-8275 1560);
PAINT SKYBLUE (-8275 1560);
FORCEPROP 1 LAST PACK_TYPE C0402
J 0
(-8275 1410);
DISPLAY 0.489362 (-8275 1410);
PAINT SKYBLUE (-8275 1410);
FORCEPROP 2 LAST CDS_LIB pure_quanta
J 0
(-8325 1560);
DISPLAY INVISIBLE (-8325 1560);
FORCEPROP 1 LAST PATH I122
J 0
(-8275 1710);
DISPLAY 0.978723 (-8275 1710);
PAINT WHITE (-8275 1710);
DISPLAY INVISIBLE (-8275 1710);
FORCEPROP 1 LAST PART_NUMBER CH5104KEB02
J 0
(-8275 1410);
DISPLAY 0.617021 (-8275 1410);
PAINT SKYBLUE (-8275 1410);
DISPLAY INVISIBLE (-8275 1410);
FORCEADD Q_CAP..1
(-7925 1525);
FORCEPROP 1 LAST LOCATION C72
J 0
(-7875 1625);
DISPLAY 0.489362 (-7875 1625);
PAINT SKYBLUE (-7875 1625);
FORCEPROP 0 LAST $SEC 1
J 0
(-7875 1675);
DISPLAY 0.680851 (-7875 1675);
PAINT MONO (-7875 1675);
DISPLAY INVISIBLE (-7875 1675);
FORCEPROP 0 LAST CDS_SEC 1
J 0
(-7875 1675);
DISPLAY 1.021277 (-7875 1675);
DISPLAY INVISIBLE (-7875 1675);
FORCEPROP 1 LASTPIN (-7925 1625) $PN 1
J 0
(-7915 1605);
DISPLAY 0.489362 (-7915 1605);
PAINT MONO (-7915 1605);
FORCEPROP 1 LASTPIN (-7925 1425) $PN 2
J 0
(-7915 1405);
DISPLAY 0.489362 (-7915 1405);
PAINT MONO (-7915 1405);
FORCEPROP 1 LAST MATERIAL X7R
J 0
(-7875 1425);
DISPLAY 0.489362 (-7875 1425);
PAINT SKYBLUE (-7875 1425);
FORCEPROP 1 LAST TOLERANCE 10%
J 0
(-7875 1475);
DISPLAY 0.489362 (-7875 1475);
PAINT SKYBLUE (-7875 1475);
FORCEPROP 1 LAST VALUE 0.1UF
J 0
(-7875 1575);
DISPLAY 0.489362 (-7875 1575);
PAINT SKYBLUE (-7875 1575);
FORCEPROP 1 LAST VOLTAGE 25V
J 0
(-7875 1525);
DISPLAY 0.489362 (-7875 1525);
PAINT SKYBLUE (-7875 1525);
FORCEPROP 1 LAST PACK_TYPE 0402
J 0
(-7875 1375);
DISPLAY 0.489362 (-7875 1375);
PAINT SKYBLUE (-7875 1375);
FORCEPROP 2 LAST CDS_LIB pure_quanta
J 0
(-7925 1525);
DISPLAY INVISIBLE (-7925 1525);
FORCEPROP 1 LAST PATH I126
J 0
(-7875 1675);
DISPLAY 0.978723 (-7875 1675);
PAINT WHITE (-7875 1675);
DISPLAY INVISIBLE (-7875 1675);
FORCEPROP 1 LAST PART_NUMBER CH4104K1B00
J 0
(-7875 1375);
DISPLAY 0.978723 (-7875 1375);
PAINT SKYBLUE (-7875 1375);
DISPLAY INVISIBLE (-7875 1375);
FORCEADD UNIVERSAL_GND..1
(-7925 1250);
FORCEPROP 3 LASTPIN (-7925 1300) SIG_NAME GND\g
J 0
(-7915 1310);
DISPLAY 0.659574 (-7915 1310);
PAINT MONO (-7915 1310);
DISPLAY INVISIBLE (-7915 1310);
FORCEPROP 1 LAST HDL_POWER GND
J 1
(-7900 1175);
DISPLAY 0.489362 (-7900 1175);
PAINT GREEN (-7900 1175);
FORCEPROP 2 LAST CDS_LIB pure_quanta_power
J 0
(-7925 1250);
DISPLAY INVISIBLE (-7925 1250);
FORCEPROP 1 LAST PATH I127
J 0
(-7850 1250);
DISPLAY 0.872340 (-7850 1250);
PAINT AQUA (-7850 1250);
DISPLAY INVISIBLE (-7850 1250);
FORCEADD Q_CAP..1
(-7675 1525);
FORCEPROP 1 LAST LOCATION C75
J 0
(-7625 1625);
DISPLAY 0.489362 (-7625 1625);
PAINT SKYBLUE (-7625 1625);
FORCEPROP 0 LAST $SEC 1
J 0
(-7625 1675);
DISPLAY 0.680851 (-7625 1675);
PAINT MONO (-7625 1675);
DISPLAY INVISIBLE (-7625 1675);
FORCEPROP 0 LAST CDS_SEC 1
J 0
(-7625 1675);
DISPLAY 1.021277 (-7625 1675);
DISPLAY INVISIBLE (-7625 1675);
FORCEPROP 1 LASTPIN (-7675 1625) $PN 1
J 0
(-7665 1605);
DISPLAY 0.489362 (-7665 1605);
PAINT MONO (-7665 1605);
FORCEPROP 1 LASTPIN (-7675 1425) $PN 2
J 0
(-7665 1405);
DISPLAY 0.489362 (-7665 1405);
PAINT MONO (-7665 1405);
FORCEPROP 1 LAST MATERIAL X7R
J 0
(-7625 1425);
DISPLAY 0.489362 (-7625 1425);
PAINT SKYBLUE (-7625 1425);
FORCEPROP 1 LAST TOLERANCE 10%
J 0
(-7625 1475);
DISPLAY 0.489362 (-7625 1475);
PAINT SKYBLUE (-7625 1475);
FORCEPROP 1 LAST VALUE 0.1UF
J 0
(-7625 1575);
DISPLAY 0.489362 (-7625 1575);
PAINT SKYBLUE (-7625 1575);
FORCEPROP 1 LAST VOLTAGE 25V
J 0
(-7625 1525);
DISPLAY 0.489362 (-7625 1525);
PAINT SKYBLUE (-7625 1525);
FORCEPROP 1 LAST PACK_TYPE 0402
J 0
(-7625 1375);
DISPLAY 0.489362 (-7625 1375);
PAINT SKYBLUE (-7625 1375);
FORCEPROP 2 LAST CDS_LIB pure_quanta
J 0
(-7675 1525);
DISPLAY INVISIBLE (-7675 1525);
FORCEPROP 1 LAST PATH I128
J 0
(-7625 1675);
DISPLAY 0.978723 (-7625 1675);
PAINT WHITE (-7625 1675);
DISPLAY INVISIBLE (-7625 1675);
FORCEPROP 1 LAST PART_NUMBER CH4104K1B00
J 0
(-7625 1375);
DISPLAY 0.978723 (-7625 1375);
PAINT SKYBLUE (-7625 1375);
DISPLAY INVISIBLE (-7625 1375);
FORCEADD UNIVERSAL_GND..1
(-7675 1250);
FORCEPROP 3 LASTPIN (-7675 1300) SIG_NAME GND\g
J 0
(-7665 1310);
DISPLAY 0.659574 (-7665 1310);
PAINT MONO (-7665 1310);
DISPLAY INVISIBLE (-7665 1310);
FORCEPROP 1 LAST HDL_POWER GND
J 1
(-7650 1175);
DISPLAY 0.489362 (-7650 1175);
PAINT GREEN (-7650 1175);
FORCEPROP 2 LAST CDS_LIB pure_quanta_power
J 0
(-7675 1250);
DISPLAY INVISIBLE (-7675 1250);
FORCEPROP 1 LAST PATH I129
J 0
(-7600 1250);
DISPLAY 0.872340 (-7600 1250);
PAINT AQUA (-7600 1250);
DISPLAY INVISIBLE (-7600 1250);
FORCEADD UNIVERSAL_GND..1
(-7450 1250);
FORCEPROP 3 LASTPIN (-7450 1300) SIG_NAME GND\g
J 0
(-7440 1310);
DISPLAY 0.659574 (-7440 1310);
PAINT MONO (-7440 1310);
DISPLAY INVISIBLE (-7440 1310);
FORCEPROP 1 LAST HDL_POWER GND
J 1
(-7425 1175);
DISPLAY 0.489362 (-7425 1175);
PAINT GREEN (-7425 1175);
FORCEPROP 2 LAST CDS_LIB pure_quanta_power
J 0
(-7450 1250);
DISPLAY INVISIBLE (-7450 1250);
FORCEPROP 1 LAST PATH I130
J 0
(-7375 1250);
DISPLAY 0.872340 (-7375 1250);
PAINT AQUA (-7375 1250);
DISPLAY INVISIBLE (-7375 1250);
FORCEADD Q_CAP..1
(-7450 1525);
FORCEPROP 1 LAST LOCATION C79
J 0
(-7400 1625);
DISPLAY 0.489362 (-7400 1625);
PAINT SKYBLUE (-7400 1625);
FORCEPROP 0 LAST $SEC 1
J 0
(-7400 1675);
DISPLAY 0.680851 (-7400 1675);
PAINT MONO (-7400 1675);
DISPLAY INVISIBLE (-7400 1675);
FORCEPROP 0 LAST CDS_SEC 1
J 0
(-7400 1675);
DISPLAY 1.021277 (-7400 1675);
DISPLAY INVISIBLE (-7400 1675);
FORCEPROP 1 LASTPIN (-7450 1625) $PN 1
J 0
(-7440 1605);
DISPLAY 0.489362 (-7440 1605);
PAINT MONO (-7440 1605);
FORCEPROP 1 LASTPIN (-7450 1425) $PN 2
J 0
(-7440 1405);
DISPLAY 0.489362 (-7440 1405);
PAINT MONO (-7440 1405);
FORCEPROP 1 LAST MATERIAL X7R
J 0
(-7400 1425);
DISPLAY 0.489362 (-7400 1425);
PAINT SKYBLUE (-7400 1425);
FORCEPROP 1 LAST TOLERANCE 10%
J 0
(-7400 1475);
DISPLAY 0.489362 (-7400 1475);
PAINT SKYBLUE (-7400 1475);
FORCEPROP 1 LAST VALUE 0.1UF
J 0
(-7400 1575);
DISPLAY 0.489362 (-7400 1575);
PAINT SKYBLUE (-7400 1575);
FORCEPROP 1 LAST VOLTAGE 25V
J 0
(-7400 1525);
DISPLAY 0.489362 (-7400 1525);
PAINT SKYBLUE (-7400 1525);
FORCEPROP 1 LAST PACK_TYPE 0402
J 0
(-7400 1375);
DISPLAY 0.489362 (-7400 1375);
PAINT SKYBLUE (-7400 1375);
FORCEPROP 2 LAST CDS_LIB pure_quanta
J 0
(-7450 1525);
DISPLAY INVISIBLE (-7450 1525);
FORCEPROP 1 LAST PATH I131
J 0
(-7400 1675);
DISPLAY 0.978723 (-7400 1675);
PAINT WHITE (-7400 1675);
DISPLAY INVISIBLE (-7400 1675);
FORCEPROP 1 LAST PART_NUMBER CH4104K1B00
J 0
(-7400 1375);
DISPLAY 0.978723 (-7400 1375);
PAINT SKYBLUE (-7400 1375);
DISPLAY INVISIBLE (-7400 1375);
FORCEADD UNIVERSAL_GND..1
(-7220 1245);
FORCEPROP 3 LASTPIN (-7220 1295) SIG_NAME GND\g
J 0
(-7210 1305);
DISPLAY 0.659574 (-7210 1305);
PAINT MONO (-7210 1305);
DISPLAY INVISIBLE (-7210 1305);
FORCEPROP 1 LAST HDL_POWER GND
J 1
(-7195 1170);
DISPLAY 0.489362 (-7195 1170);
PAINT GREEN (-7195 1170);
FORCEPROP 2 LAST CDS_LIB pure_quanta_power
J 0
(-7220 1245);
DISPLAY INVISIBLE (-7220 1245);
FORCEPROP 1 LAST PATH I137
J 0
(-7145 1245);
DISPLAY 0.872340 (-7145 1245);
PAINT AQUA (-7145 1245);
DISPLAY INVISIBLE (-7145 1245);
FORCEADD Q_CAP..1
(-7220 1520);
FORCEPROP 1 LAST LOCATION C80
J 0
(-7170 1620);
DISPLAY 0.489362 (-7170 1620);
PAINT SKYBLUE (-7170 1620);
FORCEPROP 0 LAST $SEC 1
J 0
(-7150 1675);
DISPLAY 0.680851 (-7150 1675);
PAINT MONO (-7150 1675);
DISPLAY INVISIBLE (-7150 1675);
FORCEPROP 0 LAST CDS_SEC 1
J 0
(-7150 1675);
DISPLAY 1.021277 (-7150 1675);
DISPLAY INVISIBLE (-7150 1675);
FORCEPROP 1 LASTPIN (-7220 1620) $PN 1
J 0
(-7210 1600);
DISPLAY 0.489362 (-7210 1600);
PAINT MONO (-7210 1600);
FORCEPROP 1 LASTPIN (-7220 1420) $PN 2
J 0
(-7210 1400);
DISPLAY 0.489362 (-7210 1400);
PAINT MONO (-7210 1400);
FORCEPROP 1 LAST MATERIAL X7R
J 0
(-7170 1420);
DISPLAY 0.489362 (-7170 1420);
PAINT SKYBLUE (-7170 1420);
FORCEPROP 1 LAST TOLERANCE 10%
J 0
(-7170 1470);
DISPLAY 0.489362 (-7170 1470);
PAINT SKYBLUE (-7170 1470);
FORCEPROP 1 LAST VALUE 0.1UF
J 0
(-7170 1570);
DISPLAY 0.489362 (-7170 1570);
PAINT SKYBLUE (-7170 1570);
FORCEPROP 1 LAST VOLTAGE 25V
J 0
(-7170 1520);
DISPLAY 0.489362 (-7170 1520);
PAINT SKYBLUE (-7170 1520);
FORCEPROP 1 LAST PACK_TYPE 0402
J 0
(-7170 1370);
DISPLAY 0.489362 (-7170 1370);
PAINT SKYBLUE (-7170 1370);
FORCEPROP 2 LAST CDS_LIB pure_quanta
J 0
(-7220 1520);
DISPLAY INVISIBLE (-7220 1520);
FORCEPROP 1 LAST PATH I138
J 0
(-7170 1670);
DISPLAY 0.978723 (-7170 1670);
PAINT WHITE (-7170 1670);
DISPLAY INVISIBLE (-7170 1670);
FORCEPROP 1 LAST PART_NUMBER CH4104K1B00
J 0
(-7170 1370);
DISPLAY 0.978723 (-7170 1370);
PAINT SKYBLUE (-7170 1370);
DISPLAY INVISIBLE (-7170 1370);
FORCEADD UNIVERSAL_GND..1
(-6990 1240);
FORCEPROP 3 LASTPIN (-6990 1290) SIG_NAME GND\g
J 0
(-6980 1300);
DISPLAY 0.659574 (-6980 1300);
PAINT MONO (-6980 1300);
DISPLAY INVISIBLE (-6980 1300);
FORCEPROP 1 LAST HDL_POWER GND
J 1
(-6965 1165);
DISPLAY 0.489362 (-6965 1165);
PAINT GREEN (-6965 1165);
FORCEPROP 2 LAST CDS_LIB pure_quanta_power
J 0
(-6990 1240);
DISPLAY INVISIBLE (-6990 1240);
FORCEPROP 1 LAST PATH I139
J 0
(-6915 1240);
DISPLAY 0.872340 (-6915 1240);
PAINT AQUA (-6915 1240);
DISPLAY INVISIBLE (-6915 1240);
FORCEADD Q_CAP..1
(-6990 1515);
FORCEPROP 1 LAST LOCATION C82
J 0
(-6940 1615);
DISPLAY 0.489362 (-6940 1615);
PAINT SKYBLUE (-6940 1615);
FORCEPROP 0 LAST $SEC 1
J 0
(-6925 1675);
DISPLAY 0.680851 (-6925 1675);
PAINT MONO (-6925 1675);
DISPLAY INVISIBLE (-6925 1675);
FORCEPROP 0 LAST CDS_SEC 1
J 0
(-6925 1675);
DISPLAY 1.021277 (-6925 1675);
DISPLAY INVISIBLE (-6925 1675);
FORCEPROP 1 LASTPIN (-6990 1615) $PN 1
J 0
(-6980 1595);
DISPLAY 0.489362 (-6980 1595);
PAINT MONO (-6980 1595);
FORCEPROP 1 LASTPIN (-6990 1415) $PN 2
J 0
(-6980 1395);
DISPLAY 0.489362 (-6980 1395);
PAINT MONO (-6980 1395);
FORCEPROP 1 LAST MATERIAL X7R
J 0
(-6940 1415);
DISPLAY 0.489362 (-6940 1415);
PAINT SKYBLUE (-6940 1415);
FORCEPROP 1 LAST TOLERANCE 10%
J 0
(-6940 1465);
DISPLAY 0.489362 (-6940 1465);
PAINT SKYBLUE (-6940 1465);
FORCEPROP 1 LAST VALUE 0.1UF
J 0
(-6940 1565);
DISPLAY 0.489362 (-6940 1565);
PAINT SKYBLUE (-6940 1565);
FORCEPROP 1 LAST VOLTAGE 25V
J 0
(-6940 1515);
DISPLAY 0.489362 (-6940 1515);
PAINT SKYBLUE (-6940 1515);
FORCEPROP 1 LAST PACK_TYPE 0402
J 0
(-6940 1365);
DISPLAY 0.489362 (-6940 1365);
PAINT SKYBLUE (-6940 1365);
FORCEPROP 2 LAST CDS_LIB pure_quanta
J 0
(-6990 1515);
DISPLAY INVISIBLE (-6990 1515);
FORCEPROP 1 LAST PATH I140
J 0
(-6940 1665);
DISPLAY 0.978723 (-6940 1665);
PAINT WHITE (-6940 1665);
DISPLAY INVISIBLE (-6940 1665);
FORCEPROP 1 LAST PART_NUMBER CH4104K1B00
J 0
(-6940 1365);
DISPLAY 0.978723 (-6940 1365);
PAINT SKYBLUE (-6940 1365);
DISPLAY INVISIBLE (-6940 1365);
FORCEADD UNIVERSAL_POWER..1
(-8850 2350);
FORCEPROP 3 LASTPIN (-8850 2300) SIG_NAME P3V3\g
J 0
(-8840 2310);
DISPLAY 0.659574 (-8840 2310);
PAINT MONO (-8840 2310);
DISPLAY INVISIBLE (-8840 2310);
FORCEPROP 1 LAST HDL_POWER P3V3
J 1
(-8850 2400);
DISPLAY 0.489362 (-8850 2400);
PAINT GREEN (-8850 2400);
FORCEPROP 2 LAST CDS_LIB pure_quanta_power
J 0
(-8850 2350);
DISPLAY INVISIBLE (-8850 2350);
FORCEPROP 1 LAST PATH I141
J 0
(-8800 2375);
DISPLAY 0.872340 (-8800 2375);
PAINT AQUA (-8800 2375);
DISPLAY INVISIBLE (-8800 2375);
FORCEADD Q_INDUCTOR..1
(-8500 2225);
FORCEPROP 1 LAST LOCATION L119
J 0
(-8625 2385);
DISPLAY 0.489362 (-8625 2385);
PAINT SKYBLUE (-8625 2385);
FORCEPROP 0 LAST $SEC 1
J 0
(-8625 2500);
DISPLAY 0.680851 (-8625 2500);
PAINT MONO (-8625 2500);
DISPLAY INVISIBLE (-8625 2500);
FORCEPROP 0 LAST CDS_SEC 1
J 0
(-8625 2500);
DISPLAY 1.021277 (-8625 2500);
DISPLAY INVISIBLE (-8625 2500);
FORCEPROP 0 LASTPIN (-8600 2200) $PN 1
J 2
(-8610 2210);
DISPLAY 0.489362 (-8610 2210);
PAINT MONO (-8610 2210);
FORCEPROP 0 LASTPIN (-8400 2200) $PN 2
J 0
(-8390 2210);
DISPLAY 0.489362 (-8390 2210);
PAINT MONO (-8390 2210);
FORCEPROP 1 LAST MATERIAL IND
J 0
(-8625 2280);
DISPLAY 0.489362 (-8625 2280);
PAINT SKYBLUE (-8625 2280);
FORCEPROP 2 LAST VALUE 330/2.5A
J 0
(-8625 2425);
DISPLAY 0.489362 (-8625 2425);
PAINT SKYBLUE (-8625 2425);
FORCEPROP 1 LAST PART_NUMBER CX12S331000
J 0
(-8625 2335);
DISPLAY 0.489362 (-8625 2335);
PAINT SKYBLUE (-8625 2335);
FORCEPROP 2 LAST PACK_TYPE SMLF
J 0
(-8625 2475);
DISPLAY 0.489362 (-8625 2475);
PAINT SKYBLUE (-8625 2475);
FORCEPROP 2 LAST CDS_LIB pure_quanta
J 0
(-8500 2225);
DISPLAY INVISIBLE (-8500 2225);
FORCEPROP 1 LAST NEEDS_NO_SIZE TRUE
J 0
(-8500 2225);
DISPLAY 0.468085 (-8500 2225);
PAINT GREEN (-8500 2225);
DISPLAY INVISIBLE (-8500 2225);
FORCEPROP 1 LAST PATH I142
J 0
(-8425 2280);
DISPLAY 0.723404 (-8425 2280);
PAINT GREEN (-8425 2280);
DISPLAY INVISIBLE (-8425 2280);
FORCEADD UNIVERSAL_POWER..1
(-7175 2400);
FORCEPROP 3 LASTPIN (-7175 2350) SIG_NAME P3V3_9ZX_VDD_4\g
J 0
(-7165 2360);
DISPLAY 0.659574 (-7165 2360);
PAINT MONO (-7165 2360);
DISPLAY INVISIBLE (-7165 2360);
FORCEPROP 1 LAST HDL_POWER P3V3_9ZX_VDD_4
J 1
(-7175 2450);
DISPLAY 0.489362 (-7175 2450);
PAINT GREEN (-7175 2450);
FORCEPROP 2 LAST CDS_LIB pure_quanta_power
J 0
(-7175 2400);
DISPLAY INVISIBLE (-7175 2400);
FORCEPROP 2 LAST BOM_COST SYS_CLOCK
J 0
(-7175 2550);
DISPLAY 0.808511 (-7175 2550);
DISPLAY INVISIBLE (-7175 2550);
FORCEPROP 1 LAST PATH I143
J 0
(-7125 2425);
DISPLAY 0.872340 (-7125 2425);
PAINT AQUA (-7125 2425);
DISPLAY INVISIBLE (-7125 2425);
FORCEPROP 0 LAST VOLTAGE 3.3
J 0
(-7175 2550);
DISPLAY 1.021277 (-7175 2550);
PAINT SKYBLUE (-7175 2550);
DISPLAY INVISIBLE (-7175 2550);
FORCEPROP 2 LAST ROOM DB2000_1_BCLK
J 0
(-7175 2500);
DISPLAY 0.808511 (-7175 2500);
PAINT RED (-7175 2500);
DISPLAY INVISIBLE (-7175 2500);
FORCEADD UNIVERSAL_POWER..1
(-9025 5575);
FORCEPROP 3 LASTPIN (-9025 5525) SIG_NAME P3V3\g
J 0
(-9015 5535);
DISPLAY 0.659574 (-9015 5535);
PAINT MONO (-9015 5535);
DISPLAY INVISIBLE (-9015 5535);
FORCEPROP 1 LAST HDL_POWER P3V3
J 1
(-9025 5625);
DISPLAY 0.489362 (-9025 5625);
PAINT GREEN (-9025 5625);
FORCEPROP 2 LAST CDS_LIB pure_quanta_power
J 0
(-9025 5575);
DISPLAY INVISIBLE (-9025 5575);
FORCEPROP 1 LAST PATH I144
J 0
(-8975 5600);
DISPLAY 0.872340 (-8975 5600);
PAINT AQUA (-8975 5600);
DISPLAY INVISIBLE (-8975 5600);
FORCEADD UNIVERSAL_GND..1
(-8500 4500);
FORCEPROP 3 LASTPIN (-8500 4550) SIG_NAME GND\g
J 0
(-8490 4560);
DISPLAY 0.659574 (-8490 4560);
PAINT MONO (-8490 4560);
DISPLAY INVISIBLE (-8490 4560);
FORCEPROP 1 LAST HDL_POWER GND
J 1
(-8475 4425);
DISPLAY 0.489362 (-8475 4425);
PAINT GREEN (-8475 4425);
FORCEPROP 2 LAST CDS_LIB pure_quanta_power
J 0
(-8500 4500);
DISPLAY INVISIBLE (-8500 4500);
FORCEPROP 1 LAST PATH I145
J 0
(-8425 4500);
DISPLAY 0.872340 (-8425 4500);
PAINT AQUA (-8425 4500);
DISPLAY INVISIBLE (-8425 4500);
FORCEADD Q_CAP..1
(-8500 4785);
FORCEPROP 1 LAST LOCATION C66
J 0
(-8450 4885);
DISPLAY 0.489362 (-8450 4885);
PAINT SKYBLUE (-8450 4885);
FORCEPROP 0 LAST $SEC 1
J 0
(-8450 4950);
DISPLAY 0.680851 (-8450 4950);
PAINT MONO (-8450 4950);
DISPLAY INVISIBLE (-8450 4950);
FORCEPROP 0 LAST CDS_SEC 1
J 0
(-8450 4950);
DISPLAY 1.021277 (-8450 4950);
DISPLAY INVISIBLE (-8450 4950);
FORCEPROP 1 LASTPIN (-8500 4885) $PN 1
J 0
(-8490 4865);
DISPLAY 0.489362 (-8490 4865);
PAINT MONO (-8490 4865);
FORCEPROP 1 LASTPIN (-8500 4685) $PN 2
J 0
(-8490 4665);
DISPLAY 0.489362 (-8490 4665);
PAINT MONO (-8490 4665);
FORCEPROP 1 LAST MATERIAL X6S
J 0
(-8450 4685);
DISPLAY 0.489362 (-8450 4685);
PAINT SKYBLUE (-8450 4685);
FORCEPROP 1 LAST TOLERANCE 10%
J 0
(-8450 4735);
DISPLAY 0.489362 (-8450 4735);
PAINT SKYBLUE (-8450 4735);
FORCEPROP 1 LAST VALUE 1UF
J 0
(-8450 4835);
DISPLAY 0.489362 (-8450 4835);
PAINT SKYBLUE (-8450 4835);
FORCEPROP 1 LAST VOLTAGE 25V
J 0
(-8450 4785);
DISPLAY 0.489362 (-8450 4785);
PAINT SKYBLUE (-8450 4785);
FORCEPROP 1 LAST PACK_TYPE C0402
J 0
(-8450 4635);
DISPLAY 0.489362 (-8450 4635);
PAINT SKYBLUE (-8450 4635);
FORCEPROP 2 LAST CDS_LIB pure_quanta
J 0
(-8500 4785);
DISPLAY INVISIBLE (-8500 4785);
FORCEPROP 1 LAST PATH I146
J 0
(-8450 4935);
DISPLAY 0.978723 (-8450 4935);
PAINT WHITE (-8450 4935);
DISPLAY INVISIBLE (-8450 4935);
FORCEPROP 1 LAST PART_NUMBER CH5104KEB02
J 0
(-8450 4635);
DISPLAY 0.617021 (-8450 4635);
PAINT SKYBLUE (-8450 4635);
DISPLAY INVISIBLE (-8450 4635);
FORCEADD UNIVERSAL_GND..1
(-8100 4475);
FORCEPROP 3 LASTPIN (-8100 4525) SIG_NAME GND\g
J 0
(-8090 4535);
DISPLAY 0.659574 (-8090 4535);
PAINT MONO (-8090 4535);
DISPLAY INVISIBLE (-8090 4535);
FORCEPROP 1 LAST HDL_POWER GND
J 1
(-8075 4400);
DISPLAY 0.489362 (-8075 4400);
PAINT GREEN (-8075 4400);
FORCEPROP 2 LAST CDS_LIB pure_quanta_power
J 0
(-8100 4475);
DISPLAY INVISIBLE (-8100 4475);
FORCEPROP 1 LAST PATH I147
J 0
(-8025 4475);
DISPLAY 0.872340 (-8025 4475);
PAINT AQUA (-8025 4475);
DISPLAY INVISIBLE (-8025 4475);
FORCEADD Q_CAP..1
(-8100 4750);
FORCEPROP 1 LAST LOCATION C2361
J 0
(-8050 4850);
DISPLAY 0.489362 (-8050 4850);
PAINT SKYBLUE (-8050 4850);
FORCEPROP 0 LAST $SEC 1
J 0
(-8050 4900);
DISPLAY 0.680851 (-8050 4900);
PAINT MONO (-8050 4900);
DISPLAY INVISIBLE (-8050 4900);
FORCEPROP 0 LAST CDS_SEC 1
J 0
(-8050 4900);
DISPLAY 1.021277 (-8050 4900);
DISPLAY INVISIBLE (-8050 4900);
FORCEPROP 1 LASTPIN (-8100 4850) $PN 1
J 0
(-8090 4830);
DISPLAY 0.489362 (-8090 4830);
PAINT MONO (-8090 4830);
FORCEPROP 1 LASTPIN (-8100 4650) $PN 2
J 0
(-8090 4630);
DISPLAY 0.489362 (-8090 4630);
PAINT MONO (-8090 4630);
FORCEPROP 1 LAST MATERIAL X7R
J 0
(-8050 4650);
DISPLAY 0.489362 (-8050 4650);
PAINT SKYBLUE (-8050 4650);
FORCEPROP 1 LAST TOLERANCE 10%
J 0
(-8050 4700);
DISPLAY 0.489362 (-8050 4700);
PAINT SKYBLUE (-8050 4700);
FORCEPROP 1 LAST VALUE 0.1UF
J 0
(-8050 4800);
DISPLAY 0.489362 (-8050 4800);
PAINT SKYBLUE (-8050 4800);
FORCEPROP 1 LAST VOLTAGE 25V
J 0
(-8050 4750);
DISPLAY 0.489362 (-8050 4750);
PAINT SKYBLUE (-8050 4750);
FORCEPROP 1 LAST PACK_TYPE 0402
J 0
(-8050 4600);
DISPLAY 0.489362 (-8050 4600);
PAINT SKYBLUE (-8050 4600);
FORCEPROP 2 LAST CDS_LIB pure_quanta
J 0
(-8100 4750);
DISPLAY INVISIBLE (-8100 4750);
FORCEPROP 1 LAST PATH I149
J 0
(-8050 4900);
DISPLAY 0.978723 (-8050 4900);
PAINT WHITE (-8050 4900);
DISPLAY INVISIBLE (-8050 4900);
FORCEPROP 1 LAST PART_NUMBER CH4104K1B00
J 0
(-8050 4600);
DISPLAY 0.978723 (-8050 4600);
PAINT SKYBLUE (-8050 4600);
DISPLAY INVISIBLE (-8050 4600);
FORCEADD Q_INDUCTOR..1
(-8675 5450);
FORCEPROP 1 LAST LOCATION L118
J 0
(-8800 5610);
DISPLAY 0.489362 (-8800 5610);
PAINT SKYBLUE (-8800 5610);
FORCEPROP 0 LAST $SEC 1
J 0
(-8800 5725);
DISPLAY 0.680851 (-8800 5725);
PAINT MONO (-8800 5725);
DISPLAY INVISIBLE (-8800 5725);
FORCEPROP 0 LAST CDS_SEC 1
J 0
(-8800 5725);
DISPLAY 1.021277 (-8800 5725);
DISPLAY INVISIBLE (-8800 5725);
FORCEPROP 0 LASTPIN (-8775 5425) $PN 1
J 2
(-8785 5435);
DISPLAY 0.489362 (-8785 5435);
PAINT MONO (-8785 5435);
FORCEPROP 0 LASTPIN (-8575 5425) $PN 2
J 0
(-8565 5435);
DISPLAY 0.489362 (-8565 5435);
PAINT MONO (-8565 5435);
FORCEPROP 1 LAST MATERIAL IND
J 0
(-8800 5505);
DISPLAY 0.489362 (-8800 5505);
PAINT SKYBLUE (-8800 5505);
FORCEPROP 2 LAST VALUE 330/2.5A
J 0
(-8800 5650);
DISPLAY 0.489362 (-8800 5650);
PAINT SKYBLUE (-8800 5650);
FORCEPROP 1 LAST PART_NUMBER CX12S331000
J 0
(-8800 5560);
DISPLAY 0.489362 (-8800 5560);
PAINT SKYBLUE (-8800 5560);
FORCEPROP 2 LAST PACK_TYPE SMLF
J 0
(-8800 5700);
DISPLAY 0.489362 (-8800 5700);
PAINT SKYBLUE (-8800 5700);
FORCEPROP 2 LAST CDS_LIB pure_quanta
J 0
(-8675 5450);
DISPLAY INVISIBLE (-8675 5450);
FORCEPROP 1 LAST NEEDS_NO_SIZE TRUE
J 0
(-8675 5450);
DISPLAY 0.468085 (-8675 5450);
PAINT GREEN (-8675 5450);
DISPLAY INVISIBLE (-8675 5450);
FORCEPROP 1 LAST PATH I151
J 0
(-8600 5505);
DISPLAY 0.723404 (-8600 5505);
PAINT GREEN (-8600 5505);
DISPLAY INVISIBLE (-8600 5505);
FORCEADD UNIVERSAL_GND..1
(-7850 4475);
FORCEPROP 3 LASTPIN (-7850 4525) SIG_NAME GND\g
J 0
(-7840 4535);
DISPLAY 0.659574 (-7840 4535);
PAINT MONO (-7840 4535);
DISPLAY INVISIBLE (-7840 4535);
FORCEPROP 1 LAST HDL_POWER GND
J 1
(-7825 4400);
DISPLAY 0.489362 (-7825 4400);
PAINT GREEN (-7825 4400);
FORCEPROP 2 LAST CDS_LIB pure_quanta_power
J 0
(-7850 4475);
DISPLAY INVISIBLE (-7850 4475);
FORCEPROP 1 LAST PATH I154
J 0
(-7775 4475);
DISPLAY 0.872340 (-7775 4475);
PAINT AQUA (-7775 4475);
DISPLAY INVISIBLE (-7775 4475);
FORCEADD UNIVERSAL_GND..1
(-7625 4475);
FORCEPROP 3 LASTPIN (-7625 4525) SIG_NAME GND\g
J 0
(-7615 4535);
DISPLAY 0.659574 (-7615 4535);
PAINT MONO (-7615 4535);
DISPLAY INVISIBLE (-7615 4535);
FORCEPROP 1 LAST HDL_POWER GND
J 1
(-7600 4400);
DISPLAY 0.489362 (-7600 4400);
PAINT GREEN (-7600 4400);
FORCEPROP 2 LAST CDS_LIB pure_quanta_power
J 0
(-7625 4475);
DISPLAY INVISIBLE (-7625 4475);
FORCEPROP 1 LAST PATH I155
J 0
(-7550 4475);
DISPLAY 0.872340 (-7550 4475);
PAINT AQUA (-7550 4475);
DISPLAY INVISIBLE (-7550 4475);
FORCEADD Q_CAP..1
(-7850 4750);
FORCEPROP 1 LAST LOCATION C74
J 0
(-7800 4850);
DISPLAY 0.489362 (-7800 4850);
PAINT SKYBLUE (-7800 4850);
FORCEPROP 0 LAST $SEC 1
J 0
(-7800 4900);
DISPLAY 0.680851 (-7800 4900);
PAINT MONO (-7800 4900);
DISPLAY INVISIBLE (-7800 4900);
FORCEPROP 0 LAST CDS_SEC 1
J 0
(-7800 4900);
DISPLAY 1.021277 (-7800 4900);
DISPLAY INVISIBLE (-7800 4900);
FORCEPROP 1 LASTPIN (-7850 4850) $PN 1
J 0
(-7840 4830);
DISPLAY 0.489362 (-7840 4830);
PAINT MONO (-7840 4830);
FORCEPROP 1 LASTPIN (-7850 4650) $PN 2
J 0
(-7840 4630);
DISPLAY 0.489362 (-7840 4630);
PAINT MONO (-7840 4630);
FORCEPROP 1 LAST MATERIAL X7R
J 0
(-7800 4650);
DISPLAY 0.489362 (-7800 4650);
PAINT SKYBLUE (-7800 4650);
FORCEPROP 1 LAST TOLERANCE 10%
J 0
(-7800 4700);
DISPLAY 0.489362 (-7800 4700);
PAINT SKYBLUE (-7800 4700);
FORCEPROP 1 LAST VALUE 0.1UF
J 0
(-7800 4800);
DISPLAY 0.489362 (-7800 4800);
PAINT SKYBLUE (-7800 4800);
FORCEPROP 1 LAST VOLTAGE 25V
J 0
(-7800 4750);
DISPLAY 0.489362 (-7800 4750);
PAINT SKYBLUE (-7800 4750);
FORCEPROP 1 LAST PACK_TYPE 0402
J 0
(-7800 4600);
DISPLAY 0.489362 (-7800 4600);
PAINT SKYBLUE (-7800 4600);
FORCEPROP 2 LAST CDS_LIB pure_quanta
J 0
(-7850 4750);
DISPLAY INVISIBLE (-7850 4750);
FORCEPROP 1 LAST PATH I156
J 0
(-7800 4900);
DISPLAY 0.978723 (-7800 4900);
PAINT WHITE (-7800 4900);
DISPLAY INVISIBLE (-7800 4900);
FORCEPROP 1 LAST PART_NUMBER CH4104K1B00
J 0
(-7800 4600);
DISPLAY 0.978723 (-7800 4600);
PAINT SKYBLUE (-7800 4600);
DISPLAY INVISIBLE (-7800 4600);
FORCEADD Q_CAP..1
(-7625 4750);
FORCEPROP 1 LAST LOCATION C77
J 0
(-7575 4850);
DISPLAY 0.489362 (-7575 4850);
PAINT SKYBLUE (-7575 4850);
FORCEPROP 0 LAST $SEC 1
J 0
(-7575 4900);
DISPLAY 0.680851 (-7575 4900);
PAINT MONO (-7575 4900);
DISPLAY INVISIBLE (-7575 4900);
FORCEPROP 0 LAST CDS_SEC 1
J 0
(-7575 4900);
DISPLAY 1.021277 (-7575 4900);
DISPLAY INVISIBLE (-7575 4900);
FORCEPROP 1 LASTPIN (-7625 4850) $PN 1
J 0
(-7615 4830);
DISPLAY 0.489362 (-7615 4830);
PAINT MONO (-7615 4830);
FORCEPROP 1 LASTPIN (-7625 4650) $PN 2
J 0
(-7615 4630);
DISPLAY 0.489362 (-7615 4630);
PAINT MONO (-7615 4630);
FORCEPROP 1 LAST MATERIAL X7R
J 0
(-7575 4650);
DISPLAY 0.489362 (-7575 4650);
PAINT SKYBLUE (-7575 4650);
FORCEPROP 1 LAST TOLERANCE 10%
J 0
(-7575 4700);
DISPLAY 0.489362 (-7575 4700);
PAINT SKYBLUE (-7575 4700);
FORCEPROP 1 LAST VALUE 0.1UF
J 0
(-7575 4800);
DISPLAY 0.489362 (-7575 4800);
PAINT SKYBLUE (-7575 4800);
FORCEPROP 1 LAST VOLTAGE 25V
J 0
(-7575 4750);
DISPLAY 0.489362 (-7575 4750);
PAINT SKYBLUE (-7575 4750);
FORCEPROP 1 LAST PACK_TYPE 0402
J 0
(-7575 4600);
DISPLAY 0.489362 (-7575 4600);
PAINT SKYBLUE (-7575 4600);
FORCEPROP 2 LAST CDS_LIB pure_quanta
J 0
(-7625 4750);
DISPLAY INVISIBLE (-7625 4750);
FORCEPROP 1 LAST PATH I158
J 0
(-7575 4900);
DISPLAY 0.978723 (-7575 4900);
PAINT WHITE (-7575 4900);
DISPLAY INVISIBLE (-7575 4900);
FORCEPROP 1 LAST PART_NUMBER CH4104K1B00
J 0
(-7575 4600);
DISPLAY 0.978723 (-7575 4600);
PAINT SKYBLUE (-7575 4600);
DISPLAY INVISIBLE (-7575 4600);
FORCEADD UNIVERSAL_GND..1
(-7395 4470);
FORCEPROP 3 LASTPIN (-7395 4520) SIG_NAME GND\g
J 0
(-7385 4530);
DISPLAY 0.659574 (-7385 4530);
PAINT MONO (-7385 4530);
DISPLAY INVISIBLE (-7385 4530);
FORCEPROP 1 LAST HDL_POWER GND
J 1
(-7370 4395);
DISPLAY 0.489362 (-7370 4395);
PAINT GREEN (-7370 4395);
FORCEPROP 2 LAST CDS_LIB pure_quanta_power
J 0
(-7395 4470);
DISPLAY INVISIBLE (-7395 4470);
FORCEPROP 1 LAST PATH I160
J 0
(-7320 4470);
DISPLAY 0.872340 (-7320 4470);
PAINT AQUA (-7320 4470);
DISPLAY INVISIBLE (-7320 4470);
FORCEADD UNIVERSAL_GND..1
(-7165 4465);
FORCEPROP 3 LASTPIN (-7165 4515) SIG_NAME GND\g
J 0
(-7155 4525);
DISPLAY 0.659574 (-7155 4525);
PAINT MONO (-7155 4525);
DISPLAY INVISIBLE (-7155 4525);
FORCEPROP 1 LAST HDL_POWER GND
J 1
(-7140 4390);
DISPLAY 0.489362 (-7140 4390);
PAINT GREEN (-7140 4390);
FORCEPROP 2 LAST CDS_LIB pure_quanta_power
J 0
(-7165 4465);
DISPLAY INVISIBLE (-7165 4465);
FORCEPROP 1 LAST PATH I161
J 0
(-7090 4465);
DISPLAY 0.872340 (-7090 4465);
PAINT AQUA (-7090 4465);
DISPLAY INVISIBLE (-7090 4465);
FORCEADD Q_CAP..1
(-7395 4745);
FORCEPROP 1 LAST LOCATION C2373
J 0
(-7345 4845);
DISPLAY 0.489362 (-7345 4845);
PAINT SKYBLUE (-7345 4845);
FORCEPROP 0 LAST $SEC 1
J 0
(-7325 4900);
DISPLAY 0.680851 (-7325 4900);
PAINT MONO (-7325 4900);
DISPLAY INVISIBLE (-7325 4900);
FORCEPROP 0 LAST CDS_SEC 1
J 0
(-7325 4900);
DISPLAY 1.021277 (-7325 4900);
DISPLAY INVISIBLE (-7325 4900);
FORCEPROP 1 LASTPIN (-7395 4845) $PN 1
J 0
(-7385 4825);
DISPLAY 0.489362 (-7385 4825);
PAINT MONO (-7385 4825);
FORCEPROP 1 LASTPIN (-7395 4645) $PN 2
J 0
(-7385 4625);
DISPLAY 0.489362 (-7385 4625);
PAINT MONO (-7385 4625);
FORCEPROP 1 LAST MATERIAL X7R
J 0
(-7345 4645);
DISPLAY 0.489362 (-7345 4645);
PAINT SKYBLUE (-7345 4645);
FORCEPROP 1 LAST TOLERANCE 10%
J 0
(-7345 4695);
DISPLAY 0.489362 (-7345 4695);
PAINT SKYBLUE (-7345 4695);
FORCEPROP 1 LAST VALUE 0.1UF
J 0
(-7345 4795);
DISPLAY 0.489362 (-7345 4795);
PAINT SKYBLUE (-7345 4795);
FORCEPROP 1 LAST VOLTAGE 25V
J 0
(-7345 4745);
DISPLAY 0.489362 (-7345 4745);
PAINT SKYBLUE (-7345 4745);
FORCEPROP 1 LAST PACK_TYPE 0402
J 0
(-7345 4595);
DISPLAY 0.489362 (-7345 4595);
PAINT SKYBLUE (-7345 4595);
FORCEPROP 2 LAST CDS_LIB pure_quanta
J 0
(-7395 4745);
DISPLAY INVISIBLE (-7395 4745);
FORCEPROP 1 LAST PATH I162
J 0
(-7345 4895);
DISPLAY 0.978723 (-7345 4895);
PAINT WHITE (-7345 4895);
DISPLAY INVISIBLE (-7345 4895);
FORCEPROP 1 LAST PART_NUMBER CH4104K1B00
J 0
(-7345 4595);
DISPLAY 0.978723 (-7345 4595);
PAINT SKYBLUE (-7345 4595);
DISPLAY INVISIBLE (-7345 4595);
FORCEADD Q_CAP..1
(-7165 4740);
FORCEPROP 1 LAST LOCATION C81
J 0
(-7115 4840);
DISPLAY 0.489362 (-7115 4840);
PAINT SKYBLUE (-7115 4840);
FORCEPROP 0 LAST $SEC 1
J 0
(-7100 4900);
DISPLAY 0.680851 (-7100 4900);
PAINT MONO (-7100 4900);
DISPLAY INVISIBLE (-7100 4900);
FORCEPROP 0 LAST CDS_SEC 1
J 0
(-7100 4900);
DISPLAY 1.021277 (-7100 4900);
DISPLAY INVISIBLE (-7100 4900);
FORCEPROP 1 LASTPIN (-7165 4840) $PN 1
J 0
(-7155 4820);
DISPLAY 0.489362 (-7155 4820);
PAINT MONO (-7155 4820);
FORCEPROP 1 LASTPIN (-7165 4640) $PN 2
J 0
(-7155 4620);
DISPLAY 0.489362 (-7155 4620);
PAINT MONO (-7155 4620);
FORCEPROP 1 LAST MATERIAL X7R
J 0
(-7115 4640);
DISPLAY 0.489362 (-7115 4640);
PAINT SKYBLUE (-7115 4640);
FORCEPROP 1 LAST TOLERANCE 10%
J 0
(-7115 4690);
DISPLAY 0.489362 (-7115 4690);
PAINT SKYBLUE (-7115 4690);
FORCEPROP 1 LAST VALUE 0.1UF
J 0
(-7115 4790);
DISPLAY 0.489362 (-7115 4790);
PAINT SKYBLUE (-7115 4790);
FORCEPROP 1 LAST VOLTAGE 25V
J 0
(-7115 4740);
DISPLAY 0.489362 (-7115 4740);
PAINT SKYBLUE (-7115 4740);
FORCEPROP 1 LAST PACK_TYPE 0402
J 0
(-7115 4590);
DISPLAY 0.489362 (-7115 4590);
PAINT SKYBLUE (-7115 4590);
FORCEPROP 2 LAST CDS_LIB pure_quanta
J 0
(-7165 4740);
DISPLAY INVISIBLE (-7165 4740);
FORCEPROP 1 LAST PATH I163
J 0
(-7115 4890);
DISPLAY 0.978723 (-7115 4890);
PAINT WHITE (-7115 4890);
DISPLAY INVISIBLE (-7115 4890);
FORCEPROP 1 LAST PART_NUMBER CH4104K1B00
J 0
(-7115 4590);
DISPLAY 0.978723 (-7115 4590);
PAINT SKYBLUE (-7115 4590);
DISPLAY INVISIBLE (-7115 4590);
FORCEADD UNIVERSAL_POWER..1
(-7350 5625);
FORCEPROP 3 LASTPIN (-7350 5575) SIG_NAME P3V3_9ZX_VDD_3\g
J 0
(-7340 5585);
DISPLAY 0.659574 (-7340 5585);
PAINT MONO (-7340 5585);
DISPLAY INVISIBLE (-7340 5585);
FORCEPROP 1 LAST HDL_POWER P3V3_9ZX_VDD_3
J 1
(-7350 5675);
DISPLAY 0.489362 (-7350 5675);
PAINT GREEN (-7350 5675);
FORCEPROP 2 LAST CDS_LIB pure_quanta_power
J 0
(-7350 5625);
DISPLAY INVISIBLE (-7350 5625);
FORCEPROP 2 LAST BOM_COST SYS_CLOCK
J 0
(-7350 5775);
DISPLAY 0.808511 (-7350 5775);
DISPLAY INVISIBLE (-7350 5775);
FORCEPROP 1 LAST PATH I166
J 0
(-7300 5650);
DISPLAY 0.872340 (-7300 5650);
PAINT AQUA (-7300 5650);
DISPLAY INVISIBLE (-7300 5650);
FORCEPROP 0 LAST VOLTAGE 3.3
J 0
(-7350 5775);
DISPLAY 1.021277 (-7350 5775);
PAINT SKYBLUE (-7350 5775);
DISPLAY INVISIBLE (-7350 5775);
FORCEPROP 2 LAST ROOM DB2000_1_BCLK
J 0
(-7350 5725);
DISPLAY 0.808511 (-7350 5725);
PAINT RED (-7350 5725);
DISPLAY INVISIBLE (-7350 5725);
FORCEADD Q_RES..1
(-7000 5425);
FORCEPROP 1 LAST LOCATION R2298
J 0
(-7050 5475);
DISPLAY 0.489362 (-7050 5475);
PAINT SKYBLUE (-7050 5475);
FORCEPROP 0 LAST $SEC 1
J 0
(-7050 5525);
DISPLAY 0.680851 (-7050 5525);
PAINT MONO (-7050 5525);
DISPLAY INVISIBLE (-7050 5525);
FORCEPROP 0 LAST CDS_SEC 1
J 0
(-7050 5525);
DISPLAY 1.021277 (-7050 5525);
DISPLAY INVISIBLE (-7050 5525);
FORCEPROP 1 LASTPIN (-7100 5425) $PN 1
J 0
(-7088 5437);
DISPLAY 0.489362 (-7088 5437);
PAINT MONO (-7088 5437);
FORCEPROP 1 LASTPIN (-6900 5425) $PN 2
J 0
(-6938 5437);
DISPLAY 0.489362 (-6938 5437);
PAINT MONO (-6938 5437);
FORCEPROP 1 LAST WATTAGE 1/10W
J 2
(-7000 5350);
DISPLAY 0.489362 (-7000 5350);
PAINT SKYBLUE (-7000 5350);
FORCEPROP 1 LAST MATERIAL CHIP
J 0
(-6975 5325);
DISPLAY 0.489362 (-6975 5325);
PAINT SKYBLUE (-6975 5325);
FORCEPROP 1 LAST TOLERANCE 1%
J 0
(-6875 5475);
DISPLAY 0.489362 (-6875 5475);
PAINT SKYBLUE (-6875 5475);
FORCEPROP 1 LAST VALUE 1
J 2
(-7075 5450);
DISPLAY 0.489362 (-7075 5450);
PAINT SKYBLUE (-7075 5450);
FORCEPROP 1 LAST PACK_TYPE 0603LF
J 0
(-6850 5375);
DISPLAY 0.489362 (-6850 5375);
PAINT SKYBLUE (-6850 5375);
FORCEPROP 2 LAST CDS_LIB pure_quanta
J 0
(-7000 5425);
DISPLAY INVISIBLE (-7000 5425);
FORCEPROP 1 LAST PATH I167
J 0
(-7050 5575);
DISPLAY 0.978723 (-7050 5575);
PAINT WHITE (-7050 5575);
DISPLAY INVISIBLE (-7050 5575);
FORCEPROP 1 LAST PART_NUMBER CS-1003F920
J 0
(-7050 5525);
DISPLAY 0.978723 (-7050 5525);
PAINT SKYBLUE (-7050 5525);
DISPLAY INVISIBLE (-7050 5525);
FORCEADD UNIVERSAL_GND..1
(-6325 1775);
FORCEPROP 3 LASTPIN (-6325 1825) SIG_NAME GND\g
J 0
(-6315 1835);
DISPLAY 0.659574 (-6315 1835);
PAINT MONO (-6315 1835);
DISPLAY INVISIBLE (-6315 1835);
FORCEPROP 1 LAST HDL_POWER GND
J 1
(-6300 1700);
DISPLAY 0.489362 (-6300 1700);
PAINT GREEN (-6300 1700);
FORCEPROP 2 LAST CDS_LIB pure_quanta_power
J 0
(-6325 1775);
DISPLAY INVISIBLE (-6325 1775);
FORCEPROP 1 LAST PATH I172
J 0
(-6250 1775);
DISPLAY 0.872340 (-6250 1775);
PAINT AQUA (-6250 1775);
DISPLAY INVISIBLE (-6250 1775);
FORCEADD Q_CAP..1
(-6325 2050);
FORCEPROP 1 LAST LOCATION C184
J 0
(-6275 2150);
DISPLAY 0.489362 (-6275 2150);
PAINT SKYBLUE (-6275 2150);
FORCEPROP 0 LAST $SEC 1
J 0
(-6275 2200);
DISPLAY 0.680851 (-6275 2200);
PAINT MONO (-6275 2200);
DISPLAY INVISIBLE (-6275 2200);
FORCEPROP 0 LAST CDS_SEC 1
J 0
(-6275 2200);
DISPLAY 1.021277 (-6275 2200);
DISPLAY INVISIBLE (-6275 2200);
FORCEPROP 1 LASTPIN (-6325 2150) $PN 1
J 0
(-6315 2130);
DISPLAY 0.489362 (-6315 2130);
PAINT MONO (-6315 2130);
FORCEPROP 1 LASTPIN (-6325 1950) $PN 2
J 0
(-6315 1930);
DISPLAY 0.489362 (-6315 1930);
PAINT MONO (-6315 1930);
FORCEPROP 1 LAST MATERIAL X6S
J 0
(-6275 1950);
DISPLAY 0.489362 (-6275 1950);
PAINT SKYBLUE (-6275 1950);
FORCEPROP 1 LAST TOLERANCE 10%
J 0
(-6275 2000);
DISPLAY 0.489362 (-6275 2000);
PAINT SKYBLUE (-6275 2000);
FORCEPROP 1 LAST VALUE 1UF
J 0
(-6275 2100);
DISPLAY 0.489362 (-6275 2100);
PAINT SKYBLUE (-6275 2100);
FORCEPROP 1 LAST VOLTAGE 25V
J 0
(-6275 2050);
DISPLAY 0.489362 (-6275 2050);
PAINT SKYBLUE (-6275 2050);
FORCEPROP 1 LAST PACK_TYPE C0402
J 0
(-6275 1900);
DISPLAY 0.489362 (-6275 1900);
PAINT SKYBLUE (-6275 1900);
FORCEPROP 2 LAST CDS_LIB pure_quanta
J 0
(-6325 2050);
DISPLAY INVISIBLE (-6325 2050);
FORCEPROP 1 LAST PATH I173
J 0
(-6275 2200);
DISPLAY 0.978723 (-6275 2200);
PAINT WHITE (-6275 2200);
DISPLAY INVISIBLE (-6275 2200);
FORCEPROP 1 LAST PART_NUMBER CH5104KEB02
J 0
(-6275 1900);
DISPLAY 0.617021 (-6275 1900);
PAINT SKYBLUE (-6275 1900);
DISPLAY INVISIBLE (-6275 1900);
FORCEADD UNIVERSAL_GND..1
(-6075 1775);
FORCEPROP 3 LASTPIN (-6075 1825) SIG_NAME GND\g
J 0
(-6065 1835);
DISPLAY 0.659574 (-6065 1835);
PAINT MONO (-6065 1835);
DISPLAY INVISIBLE (-6065 1835);
FORCEPROP 1 LAST HDL_POWER GND
J 1
(-6050 1700);
DISPLAY 0.489362 (-6050 1700);
PAINT GREEN (-6050 1700);
FORCEPROP 2 LAST CDS_LIB pure_quanta_power
J 0
(-6075 1775);
DISPLAY INVISIBLE (-6075 1775);
FORCEPROP 1 LAST PATH I174
J 0
(-6000 1775);
DISPLAY 0.872340 (-6000 1775);
PAINT AQUA (-6000 1775);
DISPLAY INVISIBLE (-6000 1775);
FORCEADD Q_CAP..1
(-6075 2050);
FORCEPROP 1 LAST LOCATION C186
J 0
(-6025 2150);
DISPLAY 0.489362 (-6025 2150);
PAINT SKYBLUE (-6025 2150);
FORCEPROP 0 LAST $SEC 1
J 0
(-6025 2200);
DISPLAY 0.680851 (-6025 2200);
PAINT MONO (-6025 2200);
DISPLAY INVISIBLE (-6025 2200);
FORCEPROP 0 LAST CDS_SEC 1
J 0
(-6025 2200);
DISPLAY 1.021277 (-6025 2200);
DISPLAY INVISIBLE (-6025 2200);
FORCEPROP 1 LASTPIN (-6075 2150) $PN 1
J 0
(-6065 2130);
DISPLAY 0.489362 (-6065 2130);
PAINT MONO (-6065 2130);
FORCEPROP 1 LASTPIN (-6075 1950) $PN 2
J 0
(-6065 1930);
DISPLAY 0.489362 (-6065 1930);
PAINT MONO (-6065 1930);
FORCEPROP 1 LAST MATERIAL X7R
J 0
(-6025 1950);
DISPLAY 0.489362 (-6025 1950);
PAINT SKYBLUE (-6025 1950);
FORCEPROP 1 LAST TOLERANCE 10%
J 0
(-6025 2000);
DISPLAY 0.489362 (-6025 2000);
PAINT SKYBLUE (-6025 2000);
FORCEPROP 1 LAST VALUE 0.1UF
J 0
(-6025 2100);
DISPLAY 0.489362 (-6025 2100);
PAINT SKYBLUE (-6025 2100);
FORCEPROP 1 LAST VOLTAGE 25V
J 0
(-6025 2050);
DISPLAY 0.489362 (-6025 2050);
PAINT SKYBLUE (-6025 2050);
FORCEPROP 1 LAST PACK_TYPE 0402
J 0
(-6025 1900);
DISPLAY 0.489362 (-6025 1900);
PAINT SKYBLUE (-6025 1900);
FORCEPROP 2 LAST CDS_LIB pure_quanta
J 0
(-6075 2050);
DISPLAY INVISIBLE (-6075 2050);
FORCEPROP 1 LAST PATH I175
J 0
(-6025 2200);
DISPLAY 0.978723 (-6025 2200);
PAINT WHITE (-6025 2200);
DISPLAY INVISIBLE (-6025 2200);
FORCEPROP 1 LAST PART_NUMBER CH4104K1B00
J 0
(-6025 1900);
DISPLAY 0.978723 (-6025 1900);
PAINT SKYBLUE (-6025 1900);
DISPLAY INVISIBLE (-6025 1900);
FORCEADD UNIVERSAL_GND..1
(-5875 1775);
FORCEPROP 3 LASTPIN (-5875 1825) SIG_NAME GND\g
J 0
(-5865 1835);
DISPLAY 0.659574 (-5865 1835);
PAINT MONO (-5865 1835);
DISPLAY INVISIBLE (-5865 1835);
FORCEPROP 1 LAST HDL_POWER GND
J 1
(-5850 1700);
DISPLAY 0.489362 (-5850 1700);
PAINT GREEN (-5850 1700);
FORCEPROP 2 LAST CDS_LIB pure_quanta_power
J 0
(-5875 1775);
DISPLAY INVISIBLE (-5875 1775);
FORCEPROP 1 LAST PATH I176
J 0
(-5800 1775);
DISPLAY 0.872340 (-5800 1775);
PAINT AQUA (-5800 1775);
DISPLAY INVISIBLE (-5800 1775);
FORCEADD Q_CAP..1
(-5875 2050);
FORCEPROP 1 LAST LOCATION C2384
J 0
(-5825 2150);
DISPLAY 0.489362 (-5825 2150);
PAINT SKYBLUE (-5825 2150);
FORCEPROP 0 LAST $SEC 1
J 0
(-5825 2200);
DISPLAY 0.680851 (-5825 2200);
PAINT MONO (-5825 2200);
DISPLAY INVISIBLE (-5825 2200);
FORCEPROP 0 LAST CDS_SEC 1
J 0
(-5825 2200);
DISPLAY 1.021277 (-5825 2200);
DISPLAY INVISIBLE (-5825 2200);
FORCEPROP 1 LASTPIN (-5875 2150) $PN 1
J 0
(-5865 2130);
DISPLAY 0.489362 (-5865 2130);
PAINT MONO (-5865 2130);
FORCEPROP 1 LASTPIN (-5875 1950) $PN 2
J 0
(-5865 1930);
DISPLAY 0.489362 (-5865 1930);
PAINT MONO (-5865 1930);
FORCEPROP 1 LAST MATERIAL X7R
J 0
(-5825 1950);
DISPLAY 0.489362 (-5825 1950);
PAINT SKYBLUE (-5825 1950);
FORCEPROP 1 LAST TOLERANCE 10%
J 0
(-5825 2000);
DISPLAY 0.489362 (-5825 2000);
PAINT SKYBLUE (-5825 2000);
FORCEPROP 1 LAST VALUE 0.1UF
J 0
(-5825 2100);
DISPLAY 0.489362 (-5825 2100);
PAINT SKYBLUE (-5825 2100);
FORCEPROP 1 LAST VOLTAGE 25V
J 0
(-5825 2050);
DISPLAY 0.489362 (-5825 2050);
PAINT SKYBLUE (-5825 2050);
FORCEPROP 1 LAST PACK_TYPE 0402
J 0
(-5825 1900);
DISPLAY 0.489362 (-5825 1900);
PAINT SKYBLUE (-5825 1900);
FORCEPROP 2 LAST CDS_LIB pure_quanta
J 0
(-5875 2050);
DISPLAY INVISIBLE (-5875 2050);
FORCEPROP 1 LAST PATH I177
J 0
(-5825 2200);
DISPLAY 0.978723 (-5825 2200);
PAINT WHITE (-5825 2200);
DISPLAY INVISIBLE (-5825 2200);
FORCEPROP 1 LAST PART_NUMBER CH4104K1B00
J 0
(-5825 1900);
DISPLAY 0.978723 (-5825 1900);
PAINT SKYBLUE (-5825 1900);
DISPLAY INVISIBLE (-5825 1900);
FORCEADD Q_RES..1
(-6825 2200);
FORCEPROP 1 LAST LOCATION R2299
J 0
(-6875 2250);
DISPLAY 0.489362 (-6875 2250);
PAINT SKYBLUE (-6875 2250);
FORCEPROP 0 LAST $SEC 1
J 0
(-6875 2300);
DISPLAY 0.680851 (-6875 2300);
PAINT MONO (-6875 2300);
DISPLAY INVISIBLE (-6875 2300);
FORCEPROP 0 LAST CDS_SEC 1
J 0
(-6875 2300);
DISPLAY 1.021277 (-6875 2300);
DISPLAY INVISIBLE (-6875 2300);
FORCEPROP 1 LASTPIN (-6925 2200) $PN 1
J 0
(-6913 2212);
DISPLAY 0.489362 (-6913 2212);
PAINT MONO (-6913 2212);
FORCEPROP 1 LASTPIN (-6725 2200) $PN 2
J 0
(-6763 2212);
DISPLAY 0.489362 (-6763 2212);
PAINT MONO (-6763 2212);
FORCEPROP 1 LAST WATTAGE 1/10W
J 2
(-6825 2125);
DISPLAY 0.489362 (-6825 2125);
PAINT SKYBLUE (-6825 2125);
FORCEPROP 1 LAST MATERIAL CHIP
J 0
(-6800 2100);
DISPLAY 0.489362 (-6800 2100);
PAINT SKYBLUE (-6800 2100);
FORCEPROP 1 LAST TOLERANCE 1%
J 0
(-6700 2250);
DISPLAY 0.489362 (-6700 2250);
PAINT SKYBLUE (-6700 2250);
FORCEPROP 1 LAST VALUE 1
J 2
(-6900 2225);
DISPLAY 0.489362 (-6900 2225);
PAINT SKYBLUE (-6900 2225);
FORCEPROP 1 LAST PACK_TYPE 0603LF
J 0
(-6675 2150);
DISPLAY 0.489362 (-6675 2150);
PAINT SKYBLUE (-6675 2150);
FORCEPROP 2 LAST CDS_LIB pure_quanta
J 0
(-6825 2200);
DISPLAY INVISIBLE (-6825 2200);
FORCEPROP 1 LAST PATH I178
J 0
(-6875 2350);
DISPLAY 0.978723 (-6875 2350);
PAINT WHITE (-6875 2350);
DISPLAY INVISIBLE (-6875 2350);
FORCEPROP 1 LAST PART_NUMBER CS-1003F920
J 0
(-6875 2300);
DISPLAY 0.978723 (-6875 2300);
PAINT SKYBLUE (-6875 2300);
DISPLAY INVISIBLE (-6875 2300);
FORCEADD VCC_CORE..1
(-5875 2400);
FORCEPROP 3 LASTPIN (-5875 2350) SIG_NAME P3V3_9ZX_VDDA_4\g
J 0
(-5865 2360);
DISPLAY 0.659574 (-5865 2360);
PAINT MONO (-5865 2360);
DISPLAY INVISIBLE (-5865 2360);
FORCEPROP 1 LAST HDL_POWER P3V3_9ZX_VDDA_4
J 1
(-5875 2450);
DISPLAY 0.489362 (-5875 2450);
PAINT GREEN (-5875 2450);
FORCEPROP 2 LAST CDS_LIB pure_quanta_power
J 0
(-5875 2400);
DISPLAY INVISIBLE (-5875 2400);
FORCEPROP 2 LAST BOM_COST SYS_CLOCK
J 0
(-5875 2550);
DISPLAY 0.808511 (-5875 2550);
DISPLAY INVISIBLE (-5875 2550);
FORCEPROP 1 LAST PATH I179
J 0
(-5825 2425);
DISPLAY 0.872340 (-5825 2425);
PAINT AQUA (-5825 2425);
DISPLAY INVISIBLE (-5825 2425);
FORCEPROP 0 LAST VOLTAGE 3.3
J 0
(-5875 2550);
DISPLAY 1.021277 (-5875 2550);
PAINT SKYBLUE (-5875 2550);
DISPLAY INVISIBLE (-5875 2550);
FORCEPROP 2 LAST ROOM DB2000_1_BCLK
J 0
(-5875 2500);
DISPLAY 0.808511 (-5875 2500);
PAINT RED (-5875 2500);
DISPLAY INVISIBLE (-5875 2500);
FORCEADD UNIVERSAL_GND..1
(-6200 5000);
FORCEPROP 3 LASTPIN (-6200 5050) SIG_NAME GND\g
J 0
(-6190 5060);
DISPLAY 0.659574 (-6190 5060);
PAINT MONO (-6190 5060);
DISPLAY INVISIBLE (-6190 5060);
FORCEPROP 1 LAST HDL_POWER GND
J 1
(-6175 4925);
DISPLAY 0.489362 (-6175 4925);
PAINT GREEN (-6175 4925);
FORCEPROP 2 LAST CDS_LIB pure_quanta_power
J 0
(-6200 5000);
DISPLAY INVISIBLE (-6200 5000);
FORCEPROP 1 LAST PATH I180
J 0
(-6125 5000);
DISPLAY 0.872340 (-6125 5000);
PAINT AQUA (-6125 5000);
DISPLAY INVISIBLE (-6125 5000);
FORCEADD UNIVERSAL_GND..1
(-5950 5000);
FORCEPROP 3 LASTPIN (-5950 5050) SIG_NAME GND\g
J 0
(-5940 5060);
DISPLAY 0.659574 (-5940 5060);
PAINT MONO (-5940 5060);
DISPLAY INVISIBLE (-5940 5060);
FORCEPROP 1 LAST HDL_POWER GND
J 1
(-5925 4925);
DISPLAY 0.489362 (-5925 4925);
PAINT GREEN (-5925 4925);
FORCEPROP 2 LAST CDS_LIB pure_quanta_power
J 0
(-5950 5000);
DISPLAY INVISIBLE (-5950 5000);
FORCEPROP 1 LAST PATH I181
J 0
(-5875 5000);
DISPLAY 0.872340 (-5875 5000);
PAINT AQUA (-5875 5000);
DISPLAY INVISIBLE (-5875 5000);
FORCEADD Q_CAP..1
(-6200 5275);
FORCEPROP 1 LAST LOCATION C2379
J 0
(-6150 5375);
DISPLAY 0.489362 (-6150 5375);
PAINT SKYBLUE (-6150 5375);
FORCEPROP 0 LAST $SEC 1
J 0
(-6150 5425);
DISPLAY 0.680851 (-6150 5425);
PAINT MONO (-6150 5425);
DISPLAY INVISIBLE (-6150 5425);
FORCEPROP 0 LAST CDS_SEC 1
J 0
(-6150 5425);
DISPLAY 1.021277 (-6150 5425);
DISPLAY INVISIBLE (-6150 5425);
FORCEPROP 1 LASTPIN (-6200 5375) $PN 1
J 0
(-6190 5355);
DISPLAY 0.489362 (-6190 5355);
PAINT MONO (-6190 5355);
FORCEPROP 1 LASTPIN (-6200 5175) $PN 2
J 0
(-6190 5155);
DISPLAY 0.489362 (-6190 5155);
PAINT MONO (-6190 5155);
FORCEPROP 1 LAST MATERIAL X6S
J 0
(-6150 5175);
DISPLAY 0.489362 (-6150 5175);
PAINT SKYBLUE (-6150 5175);
FORCEPROP 1 LAST TOLERANCE 10%
J 0
(-6150 5225);
DISPLAY 0.489362 (-6150 5225);
PAINT SKYBLUE (-6150 5225);
FORCEPROP 1 LAST VALUE 1UF
J 0
(-6150 5325);
DISPLAY 0.489362 (-6150 5325);
PAINT SKYBLUE (-6150 5325);
FORCEPROP 1 LAST VOLTAGE 25V
J 0
(-6150 5275);
DISPLAY 0.489362 (-6150 5275);
PAINT SKYBLUE (-6150 5275);
FORCEPROP 1 LAST PACK_TYPE C0402
J 0
(-6150 5125);
DISPLAY 0.489362 (-6150 5125);
PAINT SKYBLUE (-6150 5125);
FORCEPROP 2 LAST CDS_LIB pure_quanta
J 0
(-6200 5275);
DISPLAY INVISIBLE (-6200 5275);
FORCEPROP 1 LAST PATH I182
J 0
(-6150 5425);
DISPLAY 0.978723 (-6150 5425);
PAINT WHITE (-6150 5425);
DISPLAY INVISIBLE (-6150 5425);
FORCEPROP 1 LAST PART_NUMBER CH5104KEB02
J 0
(-6150 5125);
DISPLAY 0.617021 (-6150 5125);
PAINT SKYBLUE (-6150 5125);
DISPLAY INVISIBLE (-6150 5125);
FORCEADD Q_CAP..1
(-5950 5275);
FORCEPROP 1 LAST LOCATION C185
J 0
(-5900 5375);
DISPLAY 0.489362 (-5900 5375);
PAINT SKYBLUE (-5900 5375);
FORCEPROP 0 LAST $SEC 1
J 0
(-5900 5425);
DISPLAY 0.680851 (-5900 5425);
PAINT MONO (-5900 5425);
DISPLAY INVISIBLE (-5900 5425);
FORCEPROP 0 LAST CDS_SEC 1
J 0
(-5900 5425);
DISPLAY 1.021277 (-5900 5425);
DISPLAY INVISIBLE (-5900 5425);
FORCEPROP 1 LASTPIN (-5950 5375) $PN 1
J 0
(-5940 5355);
DISPLAY 0.489362 (-5940 5355);
PAINT MONO (-5940 5355);
FORCEPROP 1 LASTPIN (-5950 5175) $PN 2
J 0
(-5940 5155);
DISPLAY 0.489362 (-5940 5155);
PAINT MONO (-5940 5155);
FORCEPROP 1 LAST MATERIAL X7R
J 0
(-5900 5175);
DISPLAY 0.489362 (-5900 5175);
PAINT SKYBLUE (-5900 5175);
FORCEPROP 1 LAST TOLERANCE 10%
J 0
(-5900 5225);
DISPLAY 0.489362 (-5900 5225);
PAINT SKYBLUE (-5900 5225);
FORCEPROP 1 LAST VALUE 0.1UF
J 0
(-5900 5325);
DISPLAY 0.489362 (-5900 5325);
PAINT SKYBLUE (-5900 5325);
FORCEPROP 1 LAST VOLTAGE 25V
J 0
(-5900 5275);
DISPLAY 0.489362 (-5900 5275);
PAINT SKYBLUE (-5900 5275);
FORCEPROP 1 LAST PACK_TYPE 0402
J 0
(-5900 5125);
DISPLAY 0.489362 (-5900 5125);
PAINT SKYBLUE (-5900 5125);
FORCEPROP 2 LAST CDS_LIB pure_quanta
J 0
(-5950 5275);
DISPLAY INVISIBLE (-5950 5275);
FORCEPROP 1 LAST PATH I183
J 0
(-5900 5425);
DISPLAY 0.978723 (-5900 5425);
PAINT WHITE (-5900 5425);
DISPLAY INVISIBLE (-5900 5425);
FORCEPROP 1 LAST PART_NUMBER CH4104K1B00
J 0
(-5900 5125);
DISPLAY 0.978723 (-5900 5125);
PAINT SKYBLUE (-5900 5125);
DISPLAY INVISIBLE (-5900 5125);
FORCEADD UNIVERSAL_GND..1
(-5750 5000);
FORCEPROP 3 LASTPIN (-5750 5050) SIG_NAME GND\g
J 0
(-5740 5060);
DISPLAY 0.659574 (-5740 5060);
PAINT MONO (-5740 5060);
DISPLAY INVISIBLE (-5740 5060);
FORCEPROP 1 LAST HDL_POWER GND
J 1
(-5725 4925);
DISPLAY 0.489362 (-5725 4925);
PAINT GREEN (-5725 4925);
FORCEPROP 2 LAST CDS_LIB pure_quanta_power
J 0
(-5750 5000);
DISPLAY INVISIBLE (-5750 5000);
FORCEPROP 1 LAST PATH I184
J 0
(-5675 5000);
DISPLAY 0.872340 (-5675 5000);
PAINT AQUA (-5675 5000);
DISPLAY INVISIBLE (-5675 5000);
FORCEADD Q_CAP..1
(-5750 5275);
FORCEPROP 1 LAST LOCATION C187
J 0
(-5700 5375);
DISPLAY 0.489362 (-5700 5375);
PAINT SKYBLUE (-5700 5375);
FORCEPROP 0 LAST $SEC 1
J 0
(-5700 5425);
DISPLAY 0.680851 (-5700 5425);
PAINT MONO (-5700 5425);
DISPLAY INVISIBLE (-5700 5425);
FORCEPROP 0 LAST CDS_SEC 1
J 0
(-5700 5425);
DISPLAY 1.021277 (-5700 5425);
DISPLAY INVISIBLE (-5700 5425);
FORCEPROP 1 LASTPIN (-5750 5375) $PN 1
J 0
(-5740 5355);
DISPLAY 0.489362 (-5740 5355);
PAINT MONO (-5740 5355);
FORCEPROP 1 LASTPIN (-5750 5175) $PN 2
J 0
(-5740 5155);
DISPLAY 0.489362 (-5740 5155);
PAINT MONO (-5740 5155);
FORCEPROP 1 LAST MATERIAL X7R
J 0
(-5700 5175);
DISPLAY 0.489362 (-5700 5175);
PAINT SKYBLUE (-5700 5175);
FORCEPROP 1 LAST TOLERANCE 10%
J 0
(-5700 5225);
DISPLAY 0.489362 (-5700 5225);
PAINT SKYBLUE (-5700 5225);
FORCEPROP 1 LAST VALUE 0.1UF
J 0
(-5700 5325);
DISPLAY 0.489362 (-5700 5325);
PAINT SKYBLUE (-5700 5325);
FORCEPROP 1 LAST VOLTAGE 25V
J 0
(-5700 5275);
DISPLAY 0.489362 (-5700 5275);
PAINT SKYBLUE (-5700 5275);
FORCEPROP 1 LAST PACK_TYPE 0402
J 0
(-5700 5125);
DISPLAY 0.489362 (-5700 5125);
PAINT SKYBLUE (-5700 5125);
FORCEPROP 2 LAST CDS_LIB pure_quanta
J 0
(-5750 5275);
DISPLAY INVISIBLE (-5750 5275);
FORCEPROP 1 LAST PATH I185
J 0
(-5700 5425);
DISPLAY 0.978723 (-5700 5425);
PAINT WHITE (-5700 5425);
DISPLAY INVISIBLE (-5700 5425);
FORCEPROP 1 LAST PART_NUMBER CH4104K1B00
J 0
(-5700 5125);
DISPLAY 0.978723 (-5700 5125);
PAINT SKYBLUE (-5700 5125);
DISPLAY INVISIBLE (-5700 5125);
FORCEADD VCC_CORE..1
(-5750 5625);
FORCEPROP 3 LASTPIN (-5750 5575) SIG_NAME P3V3_9ZX_VDDA_3\g
J 0
(-5740 5585);
DISPLAY 0.659574 (-5740 5585);
PAINT MONO (-5740 5585);
DISPLAY INVISIBLE (-5740 5585);
FORCEPROP 1 LAST HDL_POWER P3V3_9ZX_VDDA_3
J 1
(-5750 5675);
DISPLAY 0.489362 (-5750 5675);
PAINT GREEN (-5750 5675);
FORCEPROP 2 LAST CDS_LIB pure_quanta_power
J 0
(-5750 5625);
DISPLAY INVISIBLE (-5750 5625);
FORCEPROP 2 LAST BOM_COST SYS_CLOCK
J 0
(-5750 5775);
DISPLAY 0.808511 (-5750 5775);
DISPLAY INVISIBLE (-5750 5775);
FORCEPROP 1 LAST PATH I186
J 0
(-5700 5650);
DISPLAY 0.872340 (-5700 5650);
PAINT AQUA (-5700 5650);
DISPLAY INVISIBLE (-5700 5650);
FORCEPROP 0 LAST VOLTAGE 3.3
J 0
(-5750 5775);
DISPLAY 1.021277 (-5750 5775);
PAINT SKYBLUE (-5750 5775);
DISPLAY INVISIBLE (-5750 5775);
FORCEPROP 2 LAST ROOM DB2000_1_BCLK
J 0
(-5750 5725);
DISPLAY 0.808511 (-5750 5725);
PAINT RED (-5750 5725);
DISPLAY INVISIBLE (-5750 5725);
FORCEADD UNIVERSAL_GND..1
(-1550 5275);
FORCEPROP 3 LASTPIN (-1550 5325) SIG_NAME GND\g
J 0
(-1540 5335);
DISPLAY 0.659574 (-1540 5335);
PAINT MONO (-1540 5335);
DISPLAY INVISIBLE (-1540 5335);
FORCEPROP 1 LAST HDL_POWER GND
J 1
(-1625 5275);
DISPLAY 0.489362 (-1625 5275);
PAINT GREEN (-1625 5275);
FORCEPROP 2 LAST CDS_LIB pure_quanta_power
J 0
(-1550 5275);
DISPLAY INVISIBLE (-1550 5275);
FORCEPROP 1 LAST PATH I187
J 0
(-1475 5275);
DISPLAY 0.872340 (-1475 5275);
PAINT AQUA (-1475 5275);
DISPLAY INVISIBLE (-1475 5275);
FORCEADD UNIVERSAL_POWER..1
(-1550 5975);
FORCEPROP 3 LASTPIN (-1550 5925) SIG_NAME P3V3\g
J 0
(-1540 5935);
DISPLAY 0.659574 (-1540 5935);
PAINT MONO (-1540 5935);
DISPLAY INVISIBLE (-1540 5935);
FORCEPROP 1 LAST HDL_POWER P3V3
J 1
(-1550 6025);
DISPLAY 0.489362 (-1550 6025);
PAINT GREEN (-1550 6025);
FORCEPROP 2 LAST CDS_LIB pure_quanta_power
J 0
(-1550 5975);
DISPLAY INVISIBLE (-1550 5975);
FORCEPROP 1 LAST PATH I188
J 0
(-1500 6000);
DISPLAY 0.872340 (-1500 6000);
PAINT AQUA (-1500 6000);
DISPLAY INVISIBLE (-1500 6000);
FORCEADD Q_RES..2
(-1550 5425);
FORCEPROP 1 LAST LOCATION R126
J 0
(-1505 5550);
DISPLAY 0.489362 (-1505 5550);
PAINT SKYBLUE (-1505 5550);
FORCEPROP 0 LAST $SEC 1
J 0
(-1500 5600);
DISPLAY 0.680851 (-1500 5600);
PAINT MONO (-1500 5600);
DISPLAY INVISIBLE (-1500 5600);
FORCEPROP 0 LAST CDS_SEC 1
J 0
(-1500 5600);
DISPLAY 1.021277 (-1500 5600);
DISPLAY INVISIBLE (-1500 5600);
FORCEPROP 1 LASTPIN (-1550 5525) $PN 1
J 0
(-1545 5487);
DISPLAY 0.489362 (-1545 5487);
PAINT MONO (-1545 5487);
FORCEPROP 1 LASTPIN (-1550 5325) $PN 2
J 0
(-1545 5335);
DISPLAY 0.489362 (-1545 5335);
PAINT MONO (-1545 5335);
FORCEPROP 1 LAST WATTAGE 1/16W
J 0
(-1510 5400);
DISPLAY 0.489362 (-1510 5400);
PAINT SKYBLUE (-1510 5400);
FORCEPROP 1 LAST MATERIAL CHIP
J 0
(-1510 5350);
DISPLAY 0.489362 (-1510 5350);
PAINT SKYBLUE (-1510 5350);
FORCEPROP 1 LAST TOLERANCE 5%
J 0
(-1505 5450);
DISPLAY 0.489362 (-1505 5450);
PAINT SKYBLUE (-1505 5450);
FORCEPROP 1 LAST VALUE 10K
J 0
(-1505 5500);
DISPLAY 0.489362 (-1505 5500);
PAINT SKYBLUE (-1505 5500);
FORCEPROP 1 LAST PACK_TYPE 0402LF
J 0
(-1500 5300);
DISPLAY 0.489362 (-1500 5300);
PAINT SKYBLUE (-1500 5300);
FORCEPROP 2 LAST CDS_LIB pure_quanta
J 0
(-1550 5425);
DISPLAY INVISIBLE (-1550 5425);
FORCEPROP 1 LAST PATH I189
J 0
(-1500 5600);
DISPLAY 0.978723 (-1500 5600);
PAINT WHITE (-1500 5600);
DISPLAY INVISIBLE (-1500 5600);
FORCEPROP 1 LAST PART_NUMBER TMP_QCS31002JB28
J 0
(-1510 5300);
DISPLAY 0.489362 (-1510 5300);
PAINT SKYBLUE (-1510 5300);
DISPLAY INVISIBLE (-1510 5300);
FORCEADD Q_RES..2
(-1550 5775);
FORCEPROP 1 LAST LOCATION R125
J 0
(-1505 5900);
DISPLAY 0.489362 (-1505 5900);
PAINT SKYBLUE (-1505 5900);
FORCEPROP 0 LAST $SEC 1
J 0
(-1500 5950);
DISPLAY 0.680851 (-1500 5950);
PAINT MONO (-1500 5950);
DISPLAY INVISIBLE (-1500 5950);
FORCEPROP 0 LAST CDS_SEC 1
J 0
(-1500 5950);
DISPLAY 1.021277 (-1500 5950);
DISPLAY INVISIBLE (-1500 5950);
FORCEPROP 1 LASTPIN (-1550 5875) $PN 1
J 0
(-1545 5837);
DISPLAY 0.489362 (-1545 5837);
PAINT MONO (-1545 5837);
FORCEPROP 1 LASTPIN (-1550 5675) $PN 2
J 0
(-1545 5685);
DISPLAY 0.489362 (-1545 5685);
PAINT MONO (-1545 5685);
FORCEPROP 1 LAST WATTAGE 1/16W
J 0
(-1510 5750);
DISPLAY 0.489362 (-1510 5750);
PAINT SKYBLUE (-1510 5750);
FORCEPROP 1 LAST MATERIAL CHIP
J 0
(-1510 5700);
DISPLAY 0.489362 (-1510 5700);
PAINT SKYBLUE (-1510 5700);
FORCEPROP 1 LAST TOLERANCE 5%
J 0
(-1505 5800);
DISPLAY 0.489362 (-1505 5800);
PAINT SKYBLUE (-1505 5800);
FORCEPROP 1 LAST VALUE 10K
J 0
(-1505 5850);
DISPLAY 0.489362 (-1505 5850);
PAINT SKYBLUE (-1505 5850);
FORCEPROP 1 LAST PACK_TYPE 0402LF
J 0
(-1500 5650);
DISPLAY 0.489362 (-1500 5650);
PAINT SKYBLUE (-1500 5650);
FORCEPROP 2 LAST CDS_LIB pure_quanta
J 0
(-1550 5775);
DISPLAY INVISIBLE (-1550 5775);
FORCEPROP 1 LAST PATH I190
J 0
(-1500 5950);
DISPLAY 0.978723 (-1500 5950);
PAINT WHITE (-1500 5950);
DISPLAY INVISIBLE (-1500 5950);
FORCEPROP 1 LAST PART_NUMBER TMP_QCS31002JB28
J 0
(-1510 5650);
DISPLAY 0.489362 (-1510 5650);
PAINT SKYBLUE (-1510 5650);
DISPLAY INVISIBLE (-1510 5650);
FORCEADD UNIVERSAL_GND..1
(-1525 2200);
FORCEPROP 3 LASTPIN (-1525 2250) SIG_NAME GND\g
J 0
(-1515 2260);
DISPLAY 0.659574 (-1515 2260);
PAINT MONO (-1515 2260);
DISPLAY INVISIBLE (-1515 2260);
FORCEPROP 1 LAST HDL_POWER GND
J 1
(-1600 2200);
DISPLAY 0.489362 (-1600 2200);
PAINT GREEN (-1600 2200);
FORCEPROP 2 LAST CDS_LIB pure_quanta_power
J 0
(-1525 2200);
DISPLAY INVISIBLE (-1525 2200);
FORCEPROP 1 LAST PATH I191
J 0
(-1450 2200);
DISPLAY 0.872340 (-1450 2200);
PAINT AQUA (-1450 2200);
DISPLAY INVISIBLE (-1450 2200);
FORCEADD UNIVERSAL_POWER..1
(-1525 2900);
FORCEPROP 3 LASTPIN (-1525 2850) SIG_NAME P3V3\g
J 0
(-1515 2860);
DISPLAY 0.659574 (-1515 2860);
PAINT MONO (-1515 2860);
DISPLAY INVISIBLE (-1515 2860);
FORCEPROP 1 LAST HDL_POWER P3V3
J 1
(-1525 2950);
DISPLAY 0.489362 (-1525 2950);
PAINT GREEN (-1525 2950);
FORCEPROP 2 LAST CDS_LIB pure_quanta_power
J 0
(-1525 2900);
DISPLAY INVISIBLE (-1525 2900);
FORCEPROP 1 LAST PATH I192
J 0
(-1475 2925);
DISPLAY 0.872340 (-1475 2925);
PAINT AQUA (-1475 2925);
DISPLAY INVISIBLE (-1475 2925);
FORCEADD Q_RES..2
(-1525 2350);
FORCEPROP 1 LAST LOCATION R124
J 0
(-1480 2475);
DISPLAY 0.489362 (-1480 2475);
PAINT SKYBLUE (-1480 2475);
FORCEPROP 0 LAST $SEC 1
J 0
(-1475 2525);
DISPLAY 0.680851 (-1475 2525);
PAINT MONO (-1475 2525);
DISPLAY INVISIBLE (-1475 2525);
FORCEPROP 0 LAST CDS_SEC 1
J 0
(-1475 2525);
DISPLAY 1.021277 (-1475 2525);
DISPLAY INVISIBLE (-1475 2525);
FORCEPROP 1 LASTPIN (-1525 2450) $PN 1
J 0
(-1520 2412);
DISPLAY 0.489362 (-1520 2412);
PAINT MONO (-1520 2412);
FORCEPROP 1 LASTPIN (-1525 2250) $PN 2
J 0
(-1520 2260);
DISPLAY 0.489362 (-1520 2260);
PAINT MONO (-1520 2260);
FORCEPROP 1 LAST WATTAGE 1/16W
J 0
(-1485 2325);
DISPLAY 0.489362 (-1485 2325);
PAINT SKYBLUE (-1485 2325);
FORCEPROP 1 LAST MATERIAL CHIP
J 0
(-1485 2275);
DISPLAY 0.489362 (-1485 2275);
PAINT SKYBLUE (-1485 2275);
FORCEPROP 1 LAST TOLERANCE 5%
J 0
(-1480 2375);
DISPLAY 0.489362 (-1480 2375);
PAINT SKYBLUE (-1480 2375);
FORCEPROP 1 LAST VALUE 10K
J 0
(-1480 2425);
DISPLAY 0.489362 (-1480 2425);
PAINT SKYBLUE (-1480 2425);
FORCEPROP 1 LAST PACK_TYPE 0402LF
J 0
(-1475 2225);
DISPLAY 0.489362 (-1475 2225);
PAINT SKYBLUE (-1475 2225);
FORCEPROP 2 LAST CDS_LIB pure_quanta
J 0
(-1525 2350);
DISPLAY INVISIBLE (-1525 2350);
FORCEPROP 1 LAST PATH I193
J 0
(-1475 2525);
DISPLAY 0.978723 (-1475 2525);
PAINT WHITE (-1475 2525);
DISPLAY INVISIBLE (-1475 2525);
FORCEPROP 1 LAST PART_NUMBER TMP_QCS31002JB28
J 0
(-1485 2225);
DISPLAY 0.489362 (-1485 2225);
PAINT SKYBLUE (-1485 2225);
DISPLAY INVISIBLE (-1485 2225);
FORCEADD Q_RES..2
(-1525 2700);
FORCEPROP 1 LAST LOCATION R123
J 0
(-1480 2825);
DISPLAY 0.489362 (-1480 2825);
PAINT SKYBLUE (-1480 2825);
FORCEPROP 0 LAST $SEC 1
J 0
(-1475 2875);
DISPLAY 0.680851 (-1475 2875);
PAINT MONO (-1475 2875);
DISPLAY INVISIBLE (-1475 2875);
FORCEPROP 0 LAST CDS_SEC 1
J 0
(-1475 2875);
DISPLAY 1.021277 (-1475 2875);
DISPLAY INVISIBLE (-1475 2875);
FORCEPROP 1 LASTPIN (-1525 2800) $PN 1
J 0
(-1520 2762);
DISPLAY 0.489362 (-1520 2762);
PAINT MONO (-1520 2762);
FORCEPROP 1 LASTPIN (-1525 2600) $PN 2
J 0
(-1520 2610);
DISPLAY 0.489362 (-1520 2610);
PAINT MONO (-1520 2610);
FORCEPROP 1 LAST WATTAGE 1/16W
J 0
(-1485 2675);
DISPLAY 0.489362 (-1485 2675);
PAINT SKYBLUE (-1485 2675);
FORCEPROP 1 LAST MATERIAL CHIP
J 0
(-1485 2625);
DISPLAY 0.489362 (-1485 2625);
PAINT SKYBLUE (-1485 2625);
FORCEPROP 1 LAST TOLERANCE 5%
J 0
(-1480 2725);
DISPLAY 0.489362 (-1480 2725);
PAINT SKYBLUE (-1480 2725);
FORCEPROP 1 LAST VALUE 10K
J 0
(-1480 2775);
DISPLAY 0.489362 (-1480 2775);
PAINT SKYBLUE (-1480 2775);
FORCEPROP 1 LAST PACK_TYPE 0402LF
J 0
(-1475 2575);
DISPLAY 0.489362 (-1475 2575);
PAINT SKYBLUE (-1475 2575);
FORCEPROP 2 LAST CDS_LIB pure_quanta
J 0
(-1525 2700);
DISPLAY INVISIBLE (-1525 2700);
FORCEPROP 1 LAST PATH I194
J 0
(-1475 2875);
DISPLAY 0.978723 (-1475 2875);
PAINT WHITE (-1475 2875);
DISPLAY INVISIBLE (-1475 2875);
FORCEPROP 1 LAST PART_NUMBER TMP_QCS31002JB28
J 0
(-1485 2575);
DISPLAY 0.489362 (-1485 2575);
PAINT SKYBLUE (-1485 2575);
DISPLAY INVISIBLE (-1485 2575);
FORCEADD UNIVERSAL_GND..1
(-2500 4025);
FORCEPROP 3 LASTPIN (-2500 4075) SIG_NAME GND\g
J 0
(-2490 4085);
DISPLAY 0.659574 (-2490 4085);
PAINT MONO (-2490 4085);
DISPLAY INVISIBLE (-2490 4085);
FORCEPROP 1 LAST HDL_POWER GND
J 1
(-2475 3950);
DISPLAY 0.489362 (-2475 3950);
PAINT GREEN (-2475 3950);
FORCEPROP 2 LAST CDS_LIB pure_quanta_power
J 0
(-2500 4025);
DISPLAY INVISIBLE (-2500 4025);
FORCEPROP 1 LAST PATH I195
J 0
(-2425 4025);
DISPLAY 0.872340 (-2425 4025);
PAINT AQUA (-2425 4025);
DISPLAY INVISIBLE (-2425 4025);
FORCEADD UNIVERSAL_GND..1
(-2175 1000);
FORCEPROP 3 LASTPIN (-2175 1050) SIG_NAME GND\g
J 0
(-2165 1060);
DISPLAY 0.659574 (-2165 1060);
PAINT MONO (-2165 1060);
DISPLAY INVISIBLE (-2165 1060);
FORCEPROP 1 LAST HDL_POWER GND
J 1
(-2150 925);
DISPLAY 0.489362 (-2150 925);
PAINT GREEN (-2150 925);
FORCEPROP 2 LAST CDS_LIB pure_quanta_power
J 0
(-2175 1000);
DISPLAY INVISIBLE (-2175 1000);
FORCEPROP 1 LAST PATH I196
J 0
(-2100 1000);
DISPLAY 0.872340 (-2100 1000);
PAINT AQUA (-2100 1000);
DISPLAY INVISIBLE (-2100 1000);
FORCEADD Q_RES..2
(-8525 3250);
FORCEPROP 1 LAST LOCATION R598
J 0
(-8480 3375);
DISPLAY 0.489362 (-8480 3375);
PAINT SKYBLUE (-8480 3375);
FORCEPROP 0 LAST $SEC 1
J 0
(-8475 3425);
DISPLAY 0.680851 (-8475 3425);
PAINT MONO (-8475 3425);
DISPLAY INVISIBLE (-8475 3425);
FORCEPROP 0 LAST CDS_SEC 1
J 0
(-8475 3425);
DISPLAY 1.021277 (-8475 3425);
DISPLAY INVISIBLE (-8475 3425);
FORCEPROP 1 LASTPIN (-8525 3350) $PN 1
J 0
(-8520 3312);
DISPLAY 0.489362 (-8520 3312);
PAINT MONO (-8520 3312);
FORCEPROP 1 LASTPIN (-8525 3150) $PN 2
J 0
(-8520 3160);
DISPLAY 0.489362 (-8520 3160);
PAINT MONO (-8520 3160);
FORCEPROP 1 LAST WATTAGE 1/16W
J 0
(-8485 3225);
DISPLAY 0.489362 (-8485 3225);
PAINT SKYBLUE (-8485 3225);
FORCEPROP 1 LAST MATERIAL CHIP
J 0
(-8485 3175);
DISPLAY 0.489362 (-8485 3175);
PAINT SKYBLUE (-8485 3175);
FORCEPROP 1 LAST TOLERANCE 5%
J 0
(-8480 3275);
DISPLAY 0.489362 (-8480 3275);
PAINT SKYBLUE (-8480 3275);
FORCEPROP 1 LAST VALUE 1K
J 0
(-8480 3325);
DISPLAY 0.489362 (-8480 3325);
PAINT SKYBLUE (-8480 3325);
FORCEPROP 1 LAST PACK_TYPE 0402LF
J 0
(-8485 3125);
DISPLAY 0.489362 (-8485 3125);
PAINT SKYBLUE (-8485 3125);
FORCEPROP 2 LAST CDS_LIB pure_quanta
J 0
(-8525 3250);
DISPLAY INVISIBLE (-8525 3250);
FORCEPROP 1 LAST PATH I197
J 0
(-8475 3425);
DISPLAY 0.978723 (-8475 3425);
PAINT WHITE (-8475 3425);
DISPLAY INVISIBLE (-8475 3425);
FORCEPROP 1 LAST PART_NUMBER TMP_QCS21002JB34
J 0
(-8485 3075);
DISPLAY 0.638298 (-8485 3075);
PAINT SKYBLUE (-8485 3075);
DISPLAY INVISIBLE (-8485 3075);
FORCEADD UNIVERSAL_POWER..1
(-8525 3925);
FORCEPROP 3 LASTPIN (-8525 3875) SIG_NAME P3V3\g
J 0
(-8515 3885);
DISPLAY 0.659574 (-8515 3885);
PAINT MONO (-8515 3885);
DISPLAY INVISIBLE (-8515 3885);
FORCEPROP 1 LAST HDL_POWER P3V3
J 1
(-8525 3975);
DISPLAY 0.489362 (-8525 3975);
PAINT GREEN (-8525 3975);
FORCEPROP 2 LAST CDS_LIB pure_quanta_power
J 0
(-8525 3925);
DISPLAY INVISIBLE (-8525 3925);
FORCEPROP 1 LAST PATH I199
J 0
(-8475 3950);
DISPLAY 0.872340 (-8475 3950);
PAINT AQUA (-8475 3950);
DISPLAY INVISIBLE (-8475 3950);
FORCEADD 9ZXL0451EKILFT..1
(-2975 1850);
FORCEPROP 1 LAST LOCATION U71
J 0
(-3441 2865);
DISPLAY 0.489362 (-3441 2865);
PAINT SKYBLUE (-3441 2865);
FORCEPROP 0 LAST $SEC 1
J 0
(-3350 3275);
DISPLAY 0.680851 (-3350 3275);
PAINT MONO (-3350 3275);
DISPLAY INVISIBLE (-3350 3275);
FORCEPROP 0 LAST CDS_SEC 1
J 0
(-3350 3275);
DISPLAY 1.021277 (-3350 3275);
DISPLAY INVISIBLE (-3350 3275);
FORCEPROP 0 LASTPIN (-3600 1625) $PN 1
J 2
(-3610 1635);
DISPLAY 0.489362 (-3610 1635);
PAINT MONO (-3610 1635);
FORCEPROP 0 LASTPIN (-2350 2325) $PN 32
J 0
(-2435 2335);
DISPLAY 0.489362 (-2435 2335);
PAINT MONO (-2435 2335);
FORCEPROP 0 LASTPIN (-2350 2125) $PN 13
J 0
(-2340 2135);
DISPLAY 0.489362 (-2340 2135);
PAINT MONO (-2340 2135);
FORCEPROP 0 LASTPIN (-2350 2075) $PN 14
J 0
(-2340 2085);
DISPLAY 0.489362 (-2340 2085);
PAINT MONO (-2340 2085);
FORCEPROP 0 LASTPIN (-2350 2025) $PN 19
J 0
(-2340 2035);
DISPLAY 0.489362 (-2340 2035);
PAINT MONO (-2340 2035);
FORCEPROP 0 LASTPIN (-2350 1975) $PN 20
J 0
(-2340 1985);
DISPLAY 0.489362 (-2340 1985);
PAINT MONO (-2340 1985);
FORCEPROP 0 LASTPIN (-2350 1925) $PN 22
J 0
(-2340 1935);
DISPLAY 0.489362 (-2340 1935);
PAINT MONO (-2340 1935);
FORCEPROP 0 LASTPIN (-2350 1875) $PN 23
J 0
(-2340 1885);
DISPLAY 0.489362 (-2340 1885);
PAINT MONO (-2340 1885);
FORCEPROP 0 LASTPIN (-2350 1825) $PN 27
J 0
(-2340 1835);
DISPLAY 0.489362 (-2340 1835);
PAINT MONO (-2340 1835);
FORCEPROP 0 LASTPIN (-2350 1775) $PN 28
J 0
(-2340 1785);
DISPLAY 0.489362 (-2340 1785);
PAINT MONO (-2340 1785);
FORCEPROP 0 LASTPIN (-3600 2025) $PN 3
J 2
(-3610 2035);
DISPLAY 0.489362 (-3610 2035);
PAINT MONO (-3610 2035);
FORCEPROP 0 LASTPIN (-3600 1975) $PN 4
J 2
(-3610 1985);
DISPLAY 0.489362 (-3610 1985);
PAINT MONO (-3610 1985);
FORCEPROP 0 LASTPIN (-2350 1225) $PN 33
J 0
(-2340 1235);
DISPLAY 0.489362 (-2340 1235);
PAINT MONO (-2340 1235);
FORCEPROP 0 LASTPIN (-3600 1575) $PN 9
J 2
(-3610 1585);
DISPLAY 0.489362 (-3610 1585);
PAINT MONO (-3610 1585);
FORCEPROP 0 LASTPIN (-3600 1525) $PN 8
J 2
(-3610 1535);
DISPLAY 0.489362 (-3610 1535);
PAINT MONO (-3610 1535);
FORCEPROP 0 LASTPIN (-3600 1375) $PN 10
J 2
(-3610 1385);
DISPLAY 0.489362 (-3610 1385);
PAINT MONO (-3610 1385);
FORCEPROP 0 LASTPIN (-3600 1325) $PN 11
J 2
(-3610 1335);
DISPLAY 0.489362 (-3610 1335);
PAINT MONO (-3610 1335);
FORCEPROP 0 LASTPIN (-3600 1275) $PN 17
J 2
(-3610 1285);
DISPLAY 0.489362 (-3610 1285);
PAINT MONO (-3610 1285);
FORCEPROP 0 LASTPIN (-3600 1225) $PN 30
J 2
(-3610 1235);
DISPLAY 0.489362 (-3610 1235);
PAINT MONO (-3610 1235);
FORCEPROP 0 LASTPIN (-3600 1725) $PN 7
J 2
(-3610 1735);
DISPLAY 0.489362 (-3610 1735);
PAINT MONO (-3610 1735);
FORCEPROP 0 LASTPIN (-3600 1775) $PN 6
J 2
(-3610 1785);
DISPLAY 0.489362 (-3610 1785);
PAINT MONO (-3610 1785);
FORCEPROP 0 LASTPIN (-3600 2475) $PN 12
J 2
(-3610 2485);
DISPLAY 0.489362 (-3610 2485);
PAINT MONO (-3610 2485);
FORCEPROP 0 LASTPIN (-3600 2425) $PN 16
J 2
(-3610 2435);
DISPLAY 0.489362 (-3610 2435);
PAINT MONO (-3610 2435);
FORCEPROP 0 LASTPIN (-3600 2375) $PN 21
J 2
(-3610 2385);
DISPLAY 0.489362 (-3610 2385);
PAINT MONO (-3610 2385);
FORCEPROP 0 LASTPIN (-3600 2325) $PN 25
J 2
(-3610 2335);
DISPLAY 0.489362 (-3610 2335);
PAINT MONO (-3610 2335);
FORCEPROP 0 LASTPIN (-3600 2275) $PN 29
J 2
(-3610 2285);
DISPLAY 0.489362 (-3610 2285);
PAINT MONO (-3610 2285);
FORCEPROP 0 LASTPIN (-2350 2475) $PN 31
J 0
(-2435 2485);
DISPLAY 0.489362 (-2435 2485);
PAINT MONO (-2435 2485);
FORCEPROP 0 LASTPIN (-3600 2175) $PN 2
J 2
(-3610 2185);
DISPLAY 0.489362 (-3610 2185);
PAINT MONO (-3610 2185);
FORCEPROP 0 LASTPIN (-2350 1575) $PN 15
J 0
(-2340 1585);
DISPLAY 0.489362 (-2340 1585);
PAINT MONO (-2340 1585);
FORCEPROP 0 LASTPIN (-2350 1525) $PN 18
J 0
(-2340 1535);
DISPLAY 0.489362 (-2340 1535);
PAINT MONO (-2340 1535);
FORCEPROP 0 LASTPIN (-2350 1475) $PN 24
J 0
(-2340 1485);
DISPLAY 0.489362 (-2340 1485);
PAINT MONO (-2340 1485);
FORCEPROP 0 LASTPIN (-2350 1425) $PN 26
J 0
(-2340 1435);
DISPLAY 0.489362 (-2340 1435);
PAINT MONO (-2340 1435);
FORCEPROP 0 LASTPIN (-3600 1875) $PN 5
J 2
(-3610 1885);
DISPLAY 0.489362 (-3610 1885);
PAINT MONO (-3610 1885);
FORCEPROP 2 LAST PART_TYPE SMLF
J 0
(-3350 3225);
DISPLAY 0.680851 (-3350 3225);
FORCEPROP 1 LAST MATERIAL IC
J 0
(-3441 2591);
DISPLAY 0.489362 (-3441 2591);
PAINT SKYBLUE (-3441 2591);
FORCEPROP 2 LAST VALUE 9ZXL0451EKILFT
J 0
(-3350 3175);
DISPLAY 0.489362 (-3350 3175);
PAINT SKYBLUE (-3350 3175);
FORCEPROP 1 LAST PART_NUMBER AL000451003
J 0
(-3441 2718);
DISPLAY 0.489362 (-3441 2718);
PAINT SKYBLUE (-3441 2718);
FORCEPROP 1 LAST NEEDS_NO_SIZE TRUE
J 0
(-2975 1850);
DISPLAY 0.723404 (-2975 1850);
PAINT GREEN (-2975 1850);
DISPLAY INVISIBLE (-2975 1850);
FORCEPROP 2 LAST CDS_LIB pure_quanta
J 0
(-2975 1850);
DISPLAY INVISIBLE (-2975 1850);
FORCEPROP 1 LAST CDS_LMAN_SYM_OUTLINE -475,725,475,-725
J 0
(-2975 1850);
DISPLAY 0.468085 (-2975 1850);
PAINT GREEN (-2975 1850);
DISPLAY INVISIBLE (-2975 1850);
FORCEPROP 1 LAST PATH I2
J 0
(-2975 1850);
DISPLAY 0.723404 (-2975 1850);
PAINT GREEN (-2975 1850);
DISPLAY INVISIBLE (-2975 1850);
FORCEADD UNIVERSAL_GND..1
(-8525 3075);
FORCEPROP 3 LASTPIN (-8525 3125) SIG_NAME GND\g
J 0
(-8515 3135);
DISPLAY 0.659574 (-8515 3135);
PAINT MONO (-8515 3135);
DISPLAY INVISIBLE (-8515 3135);
FORCEPROP 2 LAST CDS_LIB pure_quanta_power
J 0
(-8525 3075);
DISPLAY INVISIBLE (-8525 3075);
FORCEPROP 1 LAST PATH I200
J 0
(-8450 3075);
DISPLAY 0.872340 (-8450 3075);
PAINT AQUA (-8450 3075);
DISPLAY INVISIBLE (-8450 3075);
FORCEPROP 1 LAST HDL_POWER GND
J 1
(-8500 3000);
DISPLAY 0.872340 (-8500 3000);
PAINT GREEN (-8500 3000);
DISPLAY INVISIBLE (-8500 3000);
FORCEADD UNIVERSAL_POWER..1
(-8275 3925);
FORCEPROP 3 LASTPIN (-8275 3875) SIG_NAME P3V3\g
J 0
(-8265 3885);
DISPLAY 0.659574 (-8265 3885);
PAINT MONO (-8265 3885);
DISPLAY INVISIBLE (-8265 3885);
FORCEPROP 1 LAST HDL_POWER P3V3
J 1
(-8275 3975);
DISPLAY 0.489362 (-8275 3975);
PAINT GREEN (-8275 3975);
FORCEPROP 2 LAST CDS_LIB pure_quanta_power
J 0
(-8275 3925);
DISPLAY INVISIBLE (-8275 3925);
FORCEPROP 1 LAST PATH I201
J 0
(-8225 3950);
DISPLAY 0.872340 (-8225 3950);
PAINT AQUA (-8225 3950);
DISPLAY INVISIBLE (-8225 3950);
FORCEADD UNIVERSAL_GND..1
(-8275 3075);
FORCEPROP 3 LASTPIN (-8275 3125) SIG_NAME GND\g
J 0
(-8265 3135);
DISPLAY 0.659574 (-8265 3135);
PAINT MONO (-8265 3135);
DISPLAY INVISIBLE (-8265 3135);
FORCEPROP 2 LAST CDS_LIB pure_quanta_power
J 0
(-8275 3075);
DISPLAY INVISIBLE (-8275 3075);
FORCEPROP 1 LAST PATH I204
J 0
(-8200 3075);
DISPLAY 0.872340 (-8200 3075);
PAINT AQUA (-8200 3075);
DISPLAY INVISIBLE (-8200 3075);
FORCEPROP 1 LAST HDL_POWER GND
J 1
(-8250 3000);
DISPLAY 0.872340 (-8250 3000);
PAINT GREEN (-8250 3000);
DISPLAY INVISIBLE (-8250 3000);
FORCEADD OFFPAGE..1
(-4725 1975);
FORCEPROP 2 LAST $XR0 55 
J 0
(-4946 1975);
DISPLAY 0.638298 (-4946 1975);
PAINT MONO (-4946 1975);
FORCEPROP 1 LAST COMMENT_BODY TRUE
J 0
(-4600 1875);
DISPLAY 0.872340 (-4600 1875);
PAINT GREEN (-4600 1875);
DISPLAY INVISIBLE (-4600 1875);
FORCEPROP 1 LAST OFFPAGE TRUE
J 0
(-4400 1850);
DISPLAY 0.872340 (-4400 1850);
PAINT GREEN (-4400 1850);
DISPLAY INVISIBLE (-4400 1850);
FORCEPROP 2 LAST CDS_LIB standard
J 0
(-4725 1975);
DISPLAY INVISIBLE (-4725 1975);
FORCEPROP 2 LAST PATH I205
J 0
(-4925 2025);
DISPLAY 1.021277 (-4925 2025);
DISPLAY INVISIBLE (-4925 2025);
FORCEADD OFFPAGE..1
(-4725 2025);
FORCEPROP 2 LAST $XR0 55 
J 0
(-4946 2025);
DISPLAY 0.638298 (-4946 2025);
PAINT MONO (-4946 2025);
FORCEPROP 1 LAST COMMENT_BODY TRUE
J 0
(-4600 1925);
DISPLAY 0.872340 (-4600 1925);
PAINT GREEN (-4600 1925);
DISPLAY INVISIBLE (-4600 1925);
FORCEPROP 1 LAST OFFPAGE TRUE
J 0
(-4400 1900);
DISPLAY 0.872340 (-4400 1900);
PAINT GREEN (-4400 1900);
DISPLAY INVISIBLE (-4400 1900);
FORCEPROP 2 LAST CDS_LIB standard
J 0
(-4725 2025);
DISPLAY INVISIBLE (-4725 2025);
FORCEPROP 2 LAST PATH I206
J 0
(-4925 2075);
DISPLAY 1.021277 (-4925 2075);
DISPLAY INVISIBLE (-4925 2075);
FORCEADD OFFPAGE..1
(-4675 4875);
FORCEPROP 2 LAST $XR0 112 
J 0
(-4927 4875);
DISPLAY 0.638298 (-4927 4875);
PAINT MONO (-4927 4875);
FORCEPROP 1 LAST COMMENT_BODY TRUE
J 0
(-4550 4775);
DISPLAY 0.872340 (-4550 4775);
PAINT GREEN (-4550 4775);
DISPLAY INVISIBLE (-4550 4775);
FORCEPROP 1 LAST OFFPAGE TRUE
J 0
(-4350 4750);
DISPLAY 0.872340 (-4350 4750);
PAINT GREEN (-4350 4750);
DISPLAY INVISIBLE (-4350 4750);
FORCEPROP 2 LAST PATH I207
J 0
(-4625 4950);
DISPLAY 1.021277 (-4625 4950);
DISPLAY INVISIBLE (-4625 4950);
FORCEPROP 2 LAST CDS_LIB standard
J 0
(-4675 4875);
DISPLAY INVISIBLE (-4675 4875);
FORCEADD OFFPAGE..1
(-4450 1875);
FORCEPROP 2 LAST $XR0 112 
J 0
(-4702 1875);
DISPLAY 0.638298 (-4702 1875);
PAINT MONO (-4702 1875);
FORCEPROP 2 LAST CDS_LIB standard
J 0
(-4450 1875);
DISPLAY INVISIBLE (-4450 1875);
FORCEPROP 2 LAST PATH I208
J 0
(-4400 1950);
DISPLAY 1.021277 (-4400 1950);
DISPLAY INVISIBLE (-4400 1950);
FORCEPROP 1 LAST OFFPAGE TRUE
J 0
(-4125 1750);
DISPLAY 0.872340 (-4125 1750);
PAINT GREEN (-4125 1750);
DISPLAY INVISIBLE (-4125 1750);
FORCEPROP 1 LAST COMMENT_BODY TRUE
J 0
(-4325 1775);
DISPLAY 0.872340 (-4325 1775);
PAINT GREEN (-4325 1775);
DISPLAY INVISIBLE (-4325 1775);
FORCEADD OFFPAGE..1
(-5475 4725);
FORCEPROP 2 LAST $XR1 112 
J 0
(-5877 4725);
DISPLAY 0.638298 (-5877 4725);
PAINT MONO (-5877 4725);
FORCEPROP 2 LAST $XR0 111 
J 0
(-5757 4725);
DISPLAY 0.638298 (-5757 4725);
PAINT MONO (-5757 4725);
FORCEPROP 2 LAST CDS_LIB standard
J 0
(-5475 4725);
DISPLAY INVISIBLE (-5475 4725);
FORCEPROP 1 LAST COMMENT_BODY TRUE
J 0
(-5350 4625);
DISPLAY 0.872340 (-5350 4625);
PAINT GREEN (-5350 4625);
DISPLAY INVISIBLE (-5350 4625);
FORCEPROP 1 LAST OFFPAGE TRUE
J 0
(-5150 4600);
DISPLAY 0.872340 (-5150 4600);
PAINT GREEN (-5150 4600);
DISPLAY INVISIBLE (-5150 4600);
FORCEPROP 2 LAST PATH I209
J 0
(-5425 4800);
DISPLAY 1.021277 (-5425 4800);
DISPLAY INVISIBLE (-5425 4800);
FORCEADD OFFPAGE..3
R 2
(-5475 4775);
FORCEPROP 2 LAST $XR1 112 
J 0
(-5875 4775);
DISPLAY 0.638298 (-5875 4775);
PAINT MONO (-5875 4775);
FORCEPROP 2 LAST $XR0 111 
J 0
(-5755 4775);
DISPLAY 0.638298 (-5755 4775);
PAINT MONO (-5755 4775);
FORCEPROP 2 LAST CDS_LIB standard
J 0
(-5475 4775);
DISPLAY INVISIBLE (-5475 4775);
FORCEPROP 1 LAST OFFPAGE TRUE
J 2
(-5800 4650);
DISPLAY 0.872340 (-5800 4650);
PAINT GREEN (-5800 4650);
DISPLAY INVISIBLE (-5800 4650);
FORCEPROP 1 LAST COMMENT_BODY TRUE
J 2
(-5425 4675);
DISPLAY 0.872340 (-5425 4675);
PAINT PEACH (-5425 4675);
DISPLAY INVISIBLE (-5425 4675);
FORCEPROP 2 LAST PATH I210
J 0
(-5425 4850);
DISPLAY 1.021277 (-5425 4850);
DISPLAY INVISIBLE (-5425 4850);
FORCEADD Q_RES..1
(-4675 4725);
FORCEPROP 1 LAST LOCATION R629
J 0
(-4875 4725);
DISPLAY 0.489362 (-4875 4725);
PAINT SKYBLUE (-4875 4725);
FORCEPROP 0 LAST $SEC 1
J 0
(-4800 4775);
DISPLAY 0.680851 (-4800 4775);
PAINT MONO (-4800 4775);
DISPLAY INVISIBLE (-4800 4775);
FORCEPROP 0 LAST CDS_SEC 1
J 0
(-4800 4775);
DISPLAY 1.021277 (-4800 4775);
DISPLAY INVISIBLE (-4800 4775);
FORCEPROP 1 LASTPIN (-4775 4725) $PN 1
J 0
(-4763 4737);
DISPLAY 0.489362 (-4763 4737);
PAINT MONO (-4763 4737);
FORCEPROP 1 LASTPIN (-4575 4725) $PN 2
J 0
(-4613 4737);
DISPLAY 0.489362 (-4613 4737);
PAINT MONO (-4613 4737);
FORCEPROP 1 LAST VALUE 0
J 2
(-4550 4725);
DISPLAY 0.489362 (-4550 4725);
PAINT SKYBLUE (-4550 4725);
FORCEPROP 2 LAST CDS_LIB pure_quanta
J 0
(-4675 4725);
DISPLAY INVISIBLE (-4675 4725);
FORCEPROP 1 LAST PATH I211
J 0
(-4725 4875);
DISPLAY 0.978723 (-4725 4875);
PAINT WHITE (-4725 4875);
DISPLAY INVISIBLE (-4725 4875);
FORCEPROP 1 LAST WATTAGE 1/16W
J 2
(-4275 4650);
DISPLAY 0.489362 (-4275 4650);
PAINT SKYBLUE (-4275 4650);
DISPLAY INVISIBLE (-4275 4650);
FORCEPROP 1 LAST MATERIAL CHIP
J 0
(-4250 4650);
DISPLAY 0.489362 (-4250 4650);
PAINT SKYBLUE (-4250 4650);
DISPLAY INVISIBLE (-4250 4650);
FORCEPROP 1 LAST TOLERANCE 5%
J 0
(-4700 4650);
DISPLAY 0.489362 (-4700 4650);
PAINT SKYBLUE (-4700 4650);
DISPLAY INVISIBLE (-4700 4650);
FORCEPROP 1 LAST PART_NUMBER CS00002JB38
J 0
(-4650 4775);
DISPLAY 0.489362 (-4650 4775);
PAINT SKYBLUE (-4650 4775);
DISPLAY INVISIBLE (-4650 4775);
FORCEPROP 1 LAST PACK_TYPE 0402LF
J 0
(-4625 4650);
DISPLAY 0.489362 (-4625 4650);
PAINT SKYBLUE (-4625 4650);
DISPLAY INVISIBLE (-4625 4650);
FORCEADD Q_RES..1
(-4675 4775);
FORCEPROP 1 LAST LOCATION R628
J 0
(-4875 4775);
DISPLAY 0.489362 (-4875 4775);
PAINT SKYBLUE (-4875 4775);
FORCEPROP 0 LAST $SEC 1
J 0
(-4800 4825);
DISPLAY 0.680851 (-4800 4825);
PAINT MONO (-4800 4825);
DISPLAY INVISIBLE (-4800 4825);
FORCEPROP 0 LAST CDS_SEC 1
J 0
(-4800 4825);
DISPLAY 1.021277 (-4800 4825);
DISPLAY INVISIBLE (-4800 4825);
FORCEPROP 1 LASTPIN (-4775 4775) $PN 1
J 0
(-4763 4787);
DISPLAY 0.489362 (-4763 4787);
PAINT MONO (-4763 4787);
FORCEPROP 1 LASTPIN (-4575 4775) $PN 2
J 0
(-4613 4787);
DISPLAY 0.489362 (-4613 4787);
PAINT MONO (-4613 4787);
FORCEPROP 1 LAST VALUE 0
J 2
(-4550 4775);
DISPLAY 0.489362 (-4550 4775);
PAINT SKYBLUE (-4550 4775);
FORCEPROP 2 LAST CDS_LIB pure_quanta
J 0
(-4675 4775);
DISPLAY INVISIBLE (-4675 4775);
FORCEPROP 1 LAST PATH I212
J 0
(-4725 4925);
DISPLAY 0.978723 (-4725 4925);
PAINT WHITE (-4725 4925);
DISPLAY INVISIBLE (-4725 4925);
FORCEPROP 1 LAST WATTAGE 1/16W
J 2
(-4275 4700);
DISPLAY 0.489362 (-4275 4700);
PAINT SKYBLUE (-4275 4700);
DISPLAY INVISIBLE (-4275 4700);
FORCEPROP 1 LAST MATERIAL CHIP
J 0
(-4250 4700);
DISPLAY 0.489362 (-4250 4700);
PAINT SKYBLUE (-4250 4700);
DISPLAY INVISIBLE (-4250 4700);
FORCEPROP 1 LAST TOLERANCE 5%
J 0
(-4700 4700);
DISPLAY 0.489362 (-4700 4700);
PAINT SKYBLUE (-4700 4700);
DISPLAY INVISIBLE (-4700 4700);
FORCEPROP 1 LAST PART_NUMBER CS00002JB38
J 0
(-4650 4825);
DISPLAY 0.489362 (-4650 4825);
PAINT SKYBLUE (-4650 4825);
DISPLAY INVISIBLE (-4650 4825);
FORCEPROP 1 LAST PACK_TYPE 0402LF
J 0
(-4625 4700);
DISPLAY 0.489362 (-4625 4700);
PAINT SKYBLUE (-4625 4700);
DISPLAY INVISIBLE (-4625 4700);
FORCEADD OFFPAGE..1
(-5250 1725);
FORCEPROP 2 LAST $XR1 112 
J 0
(-5652 1725);
DISPLAY 0.638298 (-5652 1725);
PAINT MONO (-5652 1725);
FORCEPROP 2 LAST $XR0 111 
J 0
(-5532 1725);
DISPLAY 0.638298 (-5532 1725);
PAINT MONO (-5532 1725);
FORCEPROP 2 LAST CDS_LIB standard
J 0
(-5250 1725);
DISPLAY INVISIBLE (-5250 1725);
FORCEPROP 1 LAST COMMENT_BODY TRUE
J 0
(-5125 1625);
DISPLAY 0.872340 (-5125 1625);
PAINT GREEN (-5125 1625);
DISPLAY INVISIBLE (-5125 1625);
FORCEPROP 1 LAST OFFPAGE TRUE
J 0
(-4925 1600);
DISPLAY 0.872340 (-4925 1600);
PAINT GREEN (-4925 1600);
DISPLAY INVISIBLE (-4925 1600);
FORCEPROP 2 LAST PATH I213
J 0
(-5200 1800);
DISPLAY 1.021277 (-5200 1800);
DISPLAY INVISIBLE (-5200 1800);
FORCEADD OFFPAGE..3
R 2
(-5250 1775);
FORCEPROP 2 LAST $XR1 112 
J 0
(-5650 1775);
DISPLAY 0.638298 (-5650 1775);
PAINT MONO (-5650 1775);
FORCEPROP 2 LAST $XR0 111 
J 0
(-5530 1775);
DISPLAY 0.638298 (-5530 1775);
PAINT MONO (-5530 1775);
FORCEPROP 2 LAST CDS_LIB standard
J 0
(-5250 1775);
DISPLAY INVISIBLE (-5250 1775);
FORCEPROP 1 LAST OFFPAGE TRUE
J 2
(-5575 1650);
DISPLAY 0.872340 (-5575 1650);
PAINT GREEN (-5575 1650);
DISPLAY INVISIBLE (-5575 1650);
FORCEPROP 1 LAST COMMENT_BODY TRUE
J 2
(-5200 1675);
DISPLAY 0.872340 (-5200 1675);
PAINT PEACH (-5200 1675);
DISPLAY INVISIBLE (-5200 1675);
FORCEPROP 2 LAST PATH I214
J 0
(-5200 1850);
DISPLAY 1.021277 (-5200 1850);
DISPLAY INVISIBLE (-5200 1850);
FORCEADD Q_RES..1
(-4450 1725);
FORCEPROP 1 LAST LOCATION R631
J 0
(-4650 1725);
DISPLAY 0.489362 (-4650 1725);
PAINT SKYBLUE (-4650 1725);
FORCEPROP 0 LAST $SEC 1
J 0
(-4575 1775);
DISPLAY 0.680851 (-4575 1775);
PAINT MONO (-4575 1775);
DISPLAY INVISIBLE (-4575 1775);
FORCEPROP 0 LAST CDS_SEC 1
J 0
(-4575 1775);
DISPLAY 1.021277 (-4575 1775);
DISPLAY INVISIBLE (-4575 1775);
FORCEPROP 1 LASTPIN (-4550 1725) $PN 1
J 0
(-4538 1737);
DISPLAY 0.489362 (-4538 1737);
PAINT MONO (-4538 1737);
FORCEPROP 1 LASTPIN (-4350 1725) $PN 2
J 0
(-4388 1737);
DISPLAY 0.489362 (-4388 1737);
PAINT MONO (-4388 1737);
FORCEPROP 1 LAST VALUE 0
J 2
(-4325 1725);
DISPLAY 0.489362 (-4325 1725);
PAINT SKYBLUE (-4325 1725);
FORCEPROP 2 LAST CDS_LIB pure_quanta
J 0
(-4450 1725);
DISPLAY INVISIBLE (-4450 1725);
FORCEPROP 1 LAST PATH I215
J 0
(-4500 1875);
DISPLAY 0.978723 (-4500 1875);
PAINT WHITE (-4500 1875);
DISPLAY INVISIBLE (-4500 1875);
FORCEPROP 1 LAST WATTAGE 1/16W
J 2
(-4050 1650);
DISPLAY 0.489362 (-4050 1650);
PAINT SKYBLUE (-4050 1650);
DISPLAY INVISIBLE (-4050 1650);
FORCEPROP 1 LAST MATERIAL CHIP
J 0
(-4025 1650);
DISPLAY 0.489362 (-4025 1650);
PAINT SKYBLUE (-4025 1650);
DISPLAY INVISIBLE (-4025 1650);
FORCEPROP 1 LAST TOLERANCE 5%
J 0
(-4475 1650);
DISPLAY 0.489362 (-4475 1650);
PAINT SKYBLUE (-4475 1650);
DISPLAY INVISIBLE (-4475 1650);
FORCEPROP 1 LAST PART_NUMBER CS00002JB38
J 0
(-4425 1775);
DISPLAY 0.489362 (-4425 1775);
PAINT SKYBLUE (-4425 1775);
DISPLAY INVISIBLE (-4425 1775);
FORCEPROP 1 LAST PACK_TYPE 0402LF
J 0
(-4400 1650);
DISPLAY 0.489362 (-4400 1650);
PAINT SKYBLUE (-4400 1650);
DISPLAY INVISIBLE (-4400 1650);
FORCEADD Q_RES..1
(-4450 1775);
FORCEPROP 1 LAST LOCATION R630
J 0
(-4650 1775);
DISPLAY 0.489362 (-4650 1775);
PAINT SKYBLUE (-4650 1775);
FORCEPROP 0 LAST $SEC 1
J 0
(-4575 1825);
DISPLAY 0.680851 (-4575 1825);
PAINT MONO (-4575 1825);
DISPLAY INVISIBLE (-4575 1825);
FORCEPROP 0 LAST CDS_SEC 1
J 0
(-4575 1825);
DISPLAY 1.021277 (-4575 1825);
DISPLAY INVISIBLE (-4575 1825);
FORCEPROP 1 LASTPIN (-4550 1775) $PN 1
J 0
(-4538 1787);
DISPLAY 0.489362 (-4538 1787);
PAINT MONO (-4538 1787);
FORCEPROP 1 LASTPIN (-4350 1775) $PN 2
J 0
(-4388 1787);
DISPLAY 0.489362 (-4388 1787);
PAINT MONO (-4388 1787);
FORCEPROP 1 LAST VALUE 0
J 2
(-4325 1775);
DISPLAY 0.489362 (-4325 1775);
PAINT SKYBLUE (-4325 1775);
FORCEPROP 2 LAST CDS_LIB pure_quanta
J 0
(-4450 1775);
DISPLAY INVISIBLE (-4450 1775);
FORCEPROP 1 LAST PATH I216
J 0
(-4500 1925);
DISPLAY 0.978723 (-4500 1925);
PAINT WHITE (-4500 1925);
DISPLAY INVISIBLE (-4500 1925);
FORCEPROP 1 LAST WATTAGE 1/16W
J 2
(-4050 1700);
DISPLAY 0.489362 (-4050 1700);
PAINT SKYBLUE (-4050 1700);
DISPLAY INVISIBLE (-4050 1700);
FORCEPROP 1 LAST MATERIAL CHIP
J 0
(-4025 1700);
DISPLAY 0.489362 (-4025 1700);
PAINT SKYBLUE (-4025 1700);
DISPLAY INVISIBLE (-4025 1700);
FORCEPROP 1 LAST TOLERANCE 5%
J 0
(-4475 1700);
DISPLAY 0.489362 (-4475 1700);
PAINT SKYBLUE (-4475 1700);
DISPLAY INVISIBLE (-4475 1700);
FORCEPROP 1 LAST PART_NUMBER CS00002JB38
J 0
(-4425 1825);
DISPLAY 0.489362 (-4425 1825);
PAINT SKYBLUE (-4425 1825);
DISPLAY INVISIBLE (-4425 1825);
FORCEPROP 1 LAST PACK_TYPE 0402LF
J 0
(-4400 1700);
DISPLAY 0.489362 (-4400 1700);
PAINT SKYBLUE (-4400 1700);
DISPLAY INVISIBLE (-4400 1700);
FORCEADD Q_RES..2
(-8525 3675);
FORCEPROP 1 LAST LOCATION R627
J 0
(-8480 3800);
DISPLAY 0.489362 (-8480 3800);
PAINT SKYBLUE (-8480 3800);
FORCEPROP 0 LAST $SEC 1
J 0
(-8475 3850);
DISPLAY 0.680851 (-8475 3850);
PAINT MONO (-8475 3850);
DISPLAY INVISIBLE (-8475 3850);
FORCEPROP 0 LAST CDS_SEC 1
J 0
(-8475 3850);
DISPLAY 1.021277 (-8475 3850);
DISPLAY INVISIBLE (-8475 3850);
FORCEPROP 1 LASTPIN (-8525 3775) $PN 1
J 0
(-8520 3737);
DISPLAY 0.489362 (-8520 3737);
PAINT MONO (-8520 3737);
FORCEPROP 1 LASTPIN (-8525 3575) $PN 2
J 0
(-8520 3585);
DISPLAY 0.489362 (-8520 3585);
PAINT MONO (-8520 3585);
FORCEPROP 1 LAST WATTAGE 1/16W
J 0
(-8485 3650);
DISPLAY 0.489362 (-8485 3650);
PAINT SKYBLUE (-8485 3650);
FORCEPROP 1 LAST MATERIAL CHIP
J 0
(-8485 3600);
DISPLAY 0.489362 (-8485 3600);
PAINT SKYBLUE (-8485 3600);
FORCEPROP 1 LAST TOLERANCE 5%
J 0
(-8480 3700);
DISPLAY 0.489362 (-8480 3700);
PAINT SKYBLUE (-8480 3700);
FORCEPROP 1 LAST VALUE 1K
J 0
(-8480 3750);
DISPLAY 0.489362 (-8480 3750);
PAINT SKYBLUE (-8480 3750);
FORCEPROP 1 LAST PACK_TYPE 0402LF
J 0
(-8485 3550);
DISPLAY 0.489362 (-8485 3550);
PAINT SKYBLUE (-8485 3550);
FORCEPROP 2 LAST CDS_LIB pure_quanta
J 0
(-8525 3675);
DISPLAY INVISIBLE (-8525 3675);
FORCEPROP 1 LAST PATH I217
J 0
(-8475 3850);
DISPLAY 0.978723 (-8475 3850);
PAINT WHITE (-8475 3850);
DISPLAY INVISIBLE (-8475 3850);
FORCEPROP 1 LAST PART_NUMBER TMP_QCS21002JB34
J 0
(-8485 3500);
DISPLAY 0.638298 (-8485 3500);
PAINT SKYBLUE (-8485 3500);
DISPLAY INVISIBLE (-8485 3500);
FORCEADD Q_RES..2
(-8275 3675);
FORCEPROP 1 LAST LOCATION R611
J 0
(-8230 3800);
DISPLAY 0.489362 (-8230 3800);
PAINT SKYBLUE (-8230 3800);
FORCEPROP 0 LAST $SEC 1
J 0
(-8225 3850);
DISPLAY 0.680851 (-8225 3850);
PAINT MONO (-8225 3850);
DISPLAY INVISIBLE (-8225 3850);
FORCEPROP 0 LAST CDS_SEC 1
J 0
(-8225 3850);
DISPLAY 1.021277 (-8225 3850);
DISPLAY INVISIBLE (-8225 3850);
FORCEPROP 1 LASTPIN (-8275 3775) $PN 1
J 0
(-8270 3737);
DISPLAY 0.489362 (-8270 3737);
PAINT MONO (-8270 3737);
FORCEPROP 1 LASTPIN (-8275 3575) $PN 2
J 0
(-8270 3585);
DISPLAY 0.489362 (-8270 3585);
PAINT MONO (-8270 3585);
FORCEPROP 1 LAST WATTAGE 1/16W
J 0
(-8235 3650);
DISPLAY 0.489362 (-8235 3650);
PAINT SKYBLUE (-8235 3650);
FORCEPROP 1 LAST MATERIAL CHIP
J 0
(-8235 3600);
DISPLAY 0.489362 (-8235 3600);
PAINT SKYBLUE (-8235 3600);
FORCEPROP 1 LAST TOLERANCE 5%
J 0
(-8230 3700);
DISPLAY 0.489362 (-8230 3700);
PAINT SKYBLUE (-8230 3700);
FORCEPROP 1 LAST VALUE 1K
J 0
(-8230 3750);
DISPLAY 0.489362 (-8230 3750);
PAINT SKYBLUE (-8230 3750);
FORCEPROP 1 LAST PACK_TYPE 0402LF
J 0
(-8235 3550);
DISPLAY 0.489362 (-8235 3550);
PAINT SKYBLUE (-8235 3550);
FORCEPROP 2 LAST CDS_LIB pure_quanta
J 0
(-8275 3675);
DISPLAY INVISIBLE (-8275 3675);
FORCEPROP 1 LAST PATH I219
J 0
(-8225 3850);
DISPLAY 0.978723 (-8225 3850);
PAINT WHITE (-8225 3850);
DISPLAY INVISIBLE (-8225 3850);
FORCEPROP 1 LAST PART_NUMBER TMP_QCS21002JB34
J 0
(-8235 3500);
DISPLAY 0.638298 (-8235 3500);
PAINT SKYBLUE (-8235 3500);
DISPLAY INVISIBLE (-8235 3500);
FORCEADD Q_RES..2
(-8275 3250);
FORCEPROP 1 LAST LOCATION R609
J 0
(-8230 3375);
DISPLAY 0.489362 (-8230 3375);
PAINT SKYBLUE (-8230 3375);
FORCEPROP 0 LAST $SEC 1
J 0
(-8225 3425);
DISPLAY 0.680851 (-8225 3425);
PAINT MONO (-8225 3425);
DISPLAY INVISIBLE (-8225 3425);
FORCEPROP 0 LAST CDS_SEC 1
J 0
(-8225 3425);
DISPLAY 1.021277 (-8225 3425);
DISPLAY INVISIBLE (-8225 3425);
FORCEPROP 1 LASTPIN (-8275 3350) $PN 1
J 0
(-8270 3312);
DISPLAY 0.489362 (-8270 3312);
PAINT MONO (-8270 3312);
FORCEPROP 1 LASTPIN (-8275 3150) $PN 2
J 0
(-8270 3160);
DISPLAY 0.489362 (-8270 3160);
PAINT MONO (-8270 3160);
FORCEPROP 1 LAST WATTAGE 1/16W
J 0
(-8235 3225);
DISPLAY 0.489362 (-8235 3225);
PAINT SKYBLUE (-8235 3225);
FORCEPROP 1 LAST MATERIAL EMPTY
J 0
(-8235 3175);
DISPLAY 0.489362 (-8235 3175);
PAINT RED (-8235 3175);
FORCEPROP 1 LAST TOLERANCE 5%
J 0
(-8230 3275);
DISPLAY 0.489362 (-8230 3275);
PAINT SKYBLUE (-8230 3275);
FORCEPROP 1 LAST VALUE 1K
J 0
(-8230 3325);
DISPLAY 0.489362 (-8230 3325);
PAINT SKYBLUE (-8230 3325);
FORCEPROP 1 LAST PACK_TYPE 0402LF
J 0
(-8235 3125);
DISPLAY 0.489362 (-8235 3125);
PAINT SKYBLUE (-8235 3125);
FORCEPROP 2 LAST CDS_LIB pure_quanta
J 0
(-8275 3250);
DISPLAY INVISIBLE (-8275 3250);
FORCEPROP 1 LAST PATH I220
J 0
(-8225 3425);
DISPLAY 0.978723 (-8225 3425);
PAINT WHITE (-8225 3425);
DISPLAY INVISIBLE (-8225 3425);
FORCEPROP 1 LAST PART_NUMBER TMP_QCS21002JB34
J 0
(-8235 3075);
DISPLAY 0.638298 (-8235 3075);
PAINT SKYBLUE (-8235 3075);
DISPLAY INVISIBLE (-8235 3075);
FORCEADD OFFPAGE..2
(-7425 3525);
FORCEPROP 2 LAST $XR0 112 
J 0
(-7236 3525);
DISPLAY 0.638298 (-7236 3525);
PAINT MONO (-7236 3525);
FORCEPROP 1 LAST OFFPAGE TRUE
J 0
(-7100 3400);
DISPLAY 0.723404 (-7100 3400);
PAINT GREEN (-7100 3400);
DISPLAY INVISIBLE (-7100 3400);
FORCEPROP 1 LAST COMMENT_BODY TRUE
J 0
(-7470 3430);
DISPLAY 0.872340 (-7470 3430);
PAINT GREEN (-7470 3430);
DISPLAY INVISIBLE (-7470 3430);
FORCEPROP 2 LAST PATH I221
J 0
(-7250 3600);
DISPLAY 1.021277 (-7250 3600);
DISPLAY INVISIBLE (-7250 3600);
FORCEPROP 2 LAST CDS_LIB standard
J 0
(-7425 3525);
DISPLAY INVISIBLE (-7425 3525);
FORCEADD OFFPAGE..2
(-7425 3450);
FORCEPROP 2 LAST $XR0 112 
J 0
(-7236 3450);
DISPLAY 0.638298 (-7236 3450);
PAINT MONO (-7236 3450);
FORCEPROP 1 LAST OFFPAGE TRUE
J 0
(-7100 3325);
DISPLAY 0.723404 (-7100 3325);
PAINT GREEN (-7100 3325);
DISPLAY INVISIBLE (-7100 3325);
FORCEPROP 1 LAST COMMENT_BODY TRUE
J 0
(-7470 3355);
DISPLAY 0.872340 (-7470 3355);
PAINT GREEN (-7470 3355);
DISPLAY INVISIBLE (-7470 3355);
FORCEPROP 2 LAST PATH I222
J 0
(-7250 3525);
DISPLAY 1.021277 (-7250 3525);
DISPLAY INVISIBLE (-7250 3525);
FORCEPROP 2 LAST CDS_LIB standard
J 0
(-7425 3450);
DISPLAY INVISIBLE (-7425 3450);
FORCEADD OFFPAGE..4
(-625 4525);
FORCEPROP 2 LAST $XR0 125 
J 0
(-439 4525);
DISPLAY 0.638298 (-439 4525);
PAINT MONO (-439 4525);
FORCEPROP 2 LAST CDS_LIB standard
J 0
(-625 4525);
DISPLAY INVISIBLE (-625 4525);
FORCEPROP 1 LAST OFFPAGE TRUE
J 0
(-300 4400);
DISPLAY 0.872340 (-300 4400);
PAINT GREEN (-300 4400);
DISPLAY INVISIBLE (-300 4400);
FORCEPROP 1 LAST COMMENT_BODY TRUE
J 0
(-650 4425);
DISPLAY 0.872340 (-650 4425);
PAINT GREEN (-650 4425);
DISPLAY INVISIBLE (-650 4425);
FORCEPROP 2 LAST PATH I234
J 0
(-425 4575);
DISPLAY 0.680851 (-425 4575);
DISPLAY INVISIBLE (-425 4575);
FORCEADD OFFPAGE..4
(-625 4575);
FORCEPROP 2 LAST $XR0 124 
J 0
(-439 4575);
DISPLAY 0.638298 (-439 4575);
PAINT MONO (-439 4575);
FORCEPROP 2 LAST CDS_LIB standard
J 0
(-625 4575);
DISPLAY INVISIBLE (-625 4575);
FORCEPROP 1 LAST OFFPAGE TRUE
J 0
(-300 4450);
DISPLAY 0.872340 (-300 4450);
PAINT GREEN (-300 4450);
DISPLAY INVISIBLE (-300 4450);
FORCEPROP 1 LAST COMMENT_BODY TRUE
J 0
(-650 4475);
DISPLAY 0.872340 (-650 4475);
PAINT GREEN (-650 4475);
DISPLAY INVISIBLE (-650 4475);
FORCEPROP 2 LAST PATH I235
J 0
(-425 4625);
DISPLAY 0.680851 (-425 4625);
DISPLAY INVISIBLE (-425 4625);
FORCEADD OFFPAGE..4
(-625 4475);
FORCEPROP 2 LAST $XR0 79 
J 0
(-439 4475);
DISPLAY 0.638298 (-439 4475);
PAINT MONO (-439 4475);
FORCEPROP 2 LAST CDS_LIB standard
J 0
(-625 4475);
DISPLAY INVISIBLE (-625 4475);
FORCEPROP 1 LAST COMMENT_BODY TRUE
J 0
(-650 4375);
DISPLAY 0.872340 (-650 4375);
PAINT GREEN (-650 4375);
DISPLAY INVISIBLE (-650 4375);
FORCEPROP 1 LAST OFFPAGE TRUE
J 0
(-300 4350);
DISPLAY 0.872340 (-300 4350);
PAINT GREEN (-300 4350);
DISPLAY INVISIBLE (-300 4350);
FORCEPROP 2 LAST PATH I237
J 0
(-450 4550);
DISPLAY 0.680851 (-450 4550);
DISPLAY INVISIBLE (-450 4550);
FORCEADD Q_RES..1
(-1500 4075);
FORCEPROP 1 LAST LOCATION R1247
J 0
(-1750 4075);
DISPLAY 0.489362 (-1750 4075);
PAINT SKYBLUE (-1750 4075);
FORCEPROP 2 LAST $SEC 1
J 0
(-1550 4275);
DISPLAY 0.680851 (-1550 4275);
PAINT MONO (-1550 4275);
DISPLAY INVISIBLE (-1550 4275);
FORCEPROP 2 LAST CDS_SEC 1
J 0
(-1550 4275);
DISPLAY 0.680851 (-1550 4275);
DISPLAY INVISIBLE (-1550 4275);
FORCEPROP 1 LASTPIN (-1600 4075) $PN 1
J 0
(-1588 4087);
DISPLAY 0.489362 (-1588 4087);
PAINT MONO (-1588 4087);
FORCEPROP 1 LASTPIN (-1400 4075) $PN 2
J 0
(-1438 4087);
DISPLAY 0.489362 (-1438 4087);
PAINT MONO (-1438 4087);
FORCEPROP 1 LAST MATERIAL EMPTY
J 0
(-1350 4075);
DISPLAY 0.489362 (-1350 4075);
PAINT RED (-1350 4075);
FORCEPROP 1 LAST VALUE 100
J 2
(-1375 4075);
DISPLAY 0.489362 (-1375 4075);
PAINT SKYBLUE (-1375 4075);
FORCEPROP 2 LAST CDS_LIB pure_quanta
J 0
(-1500 4075);
DISPLAY INVISIBLE (-1500 4075);
FORCEPROP 1 LAST PATH I240
J 0
(-1550 4225);
DISPLAY 0.978723 (-1550 4225);
PAINT WHITE (-1550 4225);
DISPLAY INVISIBLE (-1550 4225);
FORCEPROP 1 LAST WATTAGE 1/16W
J 2
(-1525 3925);
DISPLAY 0.978723 (-1525 3925);
PAINT SKYBLUE (-1525 3925);
DISPLAY INVISIBLE (-1525 3925);
FORCEPROP 1 LAST TOLERANCE 1%
J 0
(-1500 3975);
DISPLAY 0.978723 (-1500 3975);
PAINT SKYBLUE (-1500 3975);
DISPLAY INVISIBLE (-1500 3975);
FORCEPROP 1 LAST PART_NUMBER TMP_QCS11002FB22
J 0
(-1550 4175);
DISPLAY 0.978723 (-1550 4175);
PAINT SKYBLUE (-1550 4175);
DISPLAY INVISIBLE (-1550 4175);
FORCEPROP 1 LAST PACK_TYPE 0402LF
J 0
(-1250 3925);
DISPLAY 0.978723 (-1250 3925);
PAINT SKYBLUE (-1250 3925);
DISPLAY INVISIBLE (-1250 3925);
FORCEADD UNIVERSAL_GND..1
(-1125 3700);
FORCEPROP 3 LASTPIN (-1125 3750) SIG_NAME GND\g
J 0
(-1115 3760);
DISPLAY 0.659574 (-1115 3760);
PAINT MONO (-1115 3760);
DISPLAY INVISIBLE (-1115 3760);
FORCEPROP 1 LAST HDL_POWER GND
J 1
(-1100 3625);
DISPLAY 0.489362 (-1100 3625);
PAINT GREEN (-1100 3625);
FORCEPROP 2 LAST CDS_LIB pure_quanta_power
J 0
(-1125 3700);
DISPLAY INVISIBLE (-1125 3700);
FORCEPROP 1 LAST PATH I241
J 0
(-1050 3700);
DISPLAY 0.872340 (-1050 3700);
PAINT AQUA (-1050 3700);
DISPLAY INVISIBLE (-1050 3700);
FORCEADD Q_RES..1
(-1500 4175);
FORCEPROP 1 LAST LOCATION R1246
J 0
(-1750 4175);
DISPLAY 0.489362 (-1750 4175);
PAINT SKYBLUE (-1750 4175);
FORCEPROP 2 LAST $SEC 1
J 0
(-1550 4375);
DISPLAY 0.680851 (-1550 4375);
PAINT MONO (-1550 4375);
DISPLAY INVISIBLE (-1550 4375);
FORCEPROP 2 LAST CDS_SEC 1
J 0
(-1550 4375);
DISPLAY 0.680851 (-1550 4375);
DISPLAY INVISIBLE (-1550 4375);
FORCEPROP 1 LASTPIN (-1600 4175) $PN 1
J 0
(-1588 4187);
DISPLAY 0.489362 (-1588 4187);
PAINT MONO (-1588 4187);
FORCEPROP 1 LASTPIN (-1400 4175) $PN 2
J 0
(-1438 4187);
DISPLAY 0.489362 (-1438 4187);
PAINT MONO (-1438 4187);
FORCEPROP 1 LAST MATERIAL EMPTY
J 0
(-1350 4175);
DISPLAY 0.489362 (-1350 4175);
PAINT RED (-1350 4175);
FORCEPROP 1 LAST VALUE 100
J 2
(-1375 4175);
DISPLAY 0.489362 (-1375 4175);
PAINT SKYBLUE (-1375 4175);
FORCEPROP 2 LAST CDS_LIB pure_quanta
J 0
(-1500 4175);
DISPLAY INVISIBLE (-1500 4175);
FORCEPROP 1 LAST PATH I242
J 0
(-1550 4325);
DISPLAY 0.978723 (-1550 4325);
PAINT WHITE (-1550 4325);
DISPLAY INVISIBLE (-1550 4325);
FORCEPROP 1 LAST WATTAGE 1/16W
J 2
(-1525 4025);
DISPLAY 0.978723 (-1525 4025);
PAINT SKYBLUE (-1525 4025);
DISPLAY INVISIBLE (-1525 4025);
FORCEPROP 1 LAST TOLERANCE 1%
J 0
(-1500 4075);
DISPLAY 0.978723 (-1500 4075);
PAINT SKYBLUE (-1500 4075);
DISPLAY INVISIBLE (-1500 4075);
FORCEPROP 1 LAST PART_NUMBER TMP_QCS11002FB22
J 0
(-1550 4275);
DISPLAY 0.978723 (-1550 4275);
PAINT SKYBLUE (-1550 4275);
DISPLAY INVISIBLE (-1550 4275);
FORCEPROP 1 LAST PACK_TYPE 0402LF
J 0
(-1250 4025);
DISPLAY 0.978723 (-1250 4025);
PAINT SKYBLUE (-1250 4025);
DISPLAY INVISIBLE (-1250 4025);
FORCEADD Q_RES..1
(-1500 3975);
FORCEPROP 1 LAST LOCATION R1248
J 0
(-1750 3975);
DISPLAY 0.489362 (-1750 3975);
PAINT SKYBLUE (-1750 3975);
FORCEPROP 2 LAST $SEC 1
J 0
(-1550 4175);
DISPLAY 0.680851 (-1550 4175);
PAINT MONO (-1550 4175);
DISPLAY INVISIBLE (-1550 4175);
FORCEPROP 2 LAST CDS_SEC 1
J 0
(-1550 4175);
DISPLAY 0.680851 (-1550 4175);
DISPLAY INVISIBLE (-1550 4175);
FORCEPROP 1 LASTPIN (-1600 3975) $PN 1
J 0
(-1588 3987);
DISPLAY 0.489362 (-1588 3987);
PAINT MONO (-1588 3987);
FORCEPROP 1 LASTPIN (-1400 3975) $PN 2
J 0
(-1438 3987);
DISPLAY 0.489362 (-1438 3987);
PAINT MONO (-1438 3987);
FORCEPROP 1 LAST MATERIAL EMPTY
J 0
(-1350 3975);
DISPLAY 0.489362 (-1350 3975);
PAINT RED (-1350 3975);
FORCEPROP 1 LAST VALUE 100
J 2
(-1375 3975);
DISPLAY 0.489362 (-1375 3975);
PAINT SKYBLUE (-1375 3975);
FORCEPROP 2 LAST CDS_LIB pure_quanta
J 0
(-1500 3975);
DISPLAY INVISIBLE (-1500 3975);
FORCEPROP 1 LAST PATH I243
J 0
(-1550 4125);
DISPLAY 0.978723 (-1550 4125);
PAINT WHITE (-1550 4125);
DISPLAY INVISIBLE (-1550 4125);
FORCEPROP 1 LAST WATTAGE 1/16W
J 2
(-1525 3825);
DISPLAY 0.978723 (-1525 3825);
PAINT SKYBLUE (-1525 3825);
DISPLAY INVISIBLE (-1525 3825);
FORCEPROP 1 LAST TOLERANCE 1%
J 0
(-1500 3875);
DISPLAY 0.978723 (-1500 3875);
PAINT SKYBLUE (-1500 3875);
DISPLAY INVISIBLE (-1500 3875);
FORCEPROP 1 LAST PART_NUMBER TMP_QCS11002FB22
J 0
(-1550 4075);
DISPLAY 0.978723 (-1550 4075);
PAINT SKYBLUE (-1550 4075);
DISPLAY INVISIBLE (-1550 4075);
FORCEPROP 1 LAST PACK_TYPE 0402LF
J 0
(-1250 3825);
DISPLAY 0.978723 (-1250 3825);
PAINT SKYBLUE (-1250 3825);
DISPLAY INVISIBLE (-1250 3825);
FORCEADD OFFPAGE..4
(-525 1525);
FORCEPROP 2 LAST $XR0 127 
J 0
(-339 1525);
DISPLAY 0.638298 (-339 1525);
PAINT MONO (-339 1525);
FORCEPROP 2 LAST CDS_LIB standard
J 0
(-525 1525);
DISPLAY INVISIBLE (-525 1525);
FORCEPROP 1 LAST OFFPAGE TRUE
J 0
(-200 1400);
DISPLAY 0.872340 (-200 1400);
PAINT GREEN (-200 1400);
DISPLAY INVISIBLE (-200 1400);
FORCEPROP 1 LAST COMMENT_BODY TRUE
J 0
(-550 1425);
DISPLAY 0.872340 (-550 1425);
PAINT GREEN (-550 1425);
DISPLAY INVISIBLE (-550 1425);
FORCEPROP 2 LAST PATH I244
J 0
(-325 1575);
DISPLAY 0.680851 (-325 1575);
DISPLAY INVISIBLE (-325 1575);
FORCEADD OFFPAGE..4
(-525 1575);
FORCEPROP 2 LAST $XR0 126 
J 0
(-339 1575);
DISPLAY 0.638298 (-339 1575);
PAINT MONO (-339 1575);
FORCEPROP 2 LAST CDS_LIB standard
J 0
(-525 1575);
DISPLAY INVISIBLE (-525 1575);
FORCEPROP 1 LAST OFFPAGE TRUE
J 0
(-200 1450);
DISPLAY 0.872340 (-200 1450);
PAINT GREEN (-200 1450);
DISPLAY INVISIBLE (-200 1450);
FORCEPROP 1 LAST COMMENT_BODY TRUE
J 0
(-550 1475);
DISPLAY 0.872340 (-550 1475);
PAINT GREEN (-550 1475);
DISPLAY INVISIBLE (-550 1475);
FORCEPROP 2 LAST PATH I246
J 0
(-325 1625);
DISPLAY 0.680851 (-325 1625);
DISPLAY INVISIBLE (-325 1625);
FORCEADD Q_RES..1
(-1400 1250);
FORCEPROP 1 LAST LOCATION R1250
J 0
(-1525 1250);
DISPLAY 0.489362 (-1525 1250);
PAINT SKYBLUE (-1525 1250);
FORCEPROP 2 LAST $SEC 1
J 0
(-1450 1450);
DISPLAY 0.680851 (-1450 1450);
PAINT MONO (-1450 1450);
DISPLAY INVISIBLE (-1450 1450);
FORCEPROP 2 LAST CDS_SEC 1
J 0
(-1450 1450);
DISPLAY 0.680851 (-1450 1450);
DISPLAY INVISIBLE (-1450 1450);
FORCEPROP 1 LASTPIN (-1500 1250) $PN 1
J 0
(-1488 1262);
DISPLAY 0.489362 (-1488 1262);
PAINT MONO (-1488 1262);
FORCEPROP 1 LASTPIN (-1300 1250) $PN 2
J 0
(-1338 1262);
DISPLAY 0.489362 (-1338 1262);
PAINT MONO (-1338 1262);
FORCEPROP 1 LAST MATERIAL EMPTY
J 0
(-1250 1250);
DISPLAY 0.489362 (-1250 1250);
PAINT RED (-1250 1250);
FORCEPROP 1 LAST VALUE 100
J 2
(-1275 1250);
DISPLAY 0.489362 (-1275 1250);
PAINT SKYBLUE (-1275 1250);
FORCEPROP 2 LAST CDS_LIB pure_quanta
J 0
(-1400 1250);
DISPLAY INVISIBLE (-1400 1250);
FORCEPROP 1 LAST PATH I250
J 0
(-1450 1400);
DISPLAY 0.978723 (-1450 1400);
PAINT WHITE (-1450 1400);
DISPLAY INVISIBLE (-1450 1400);
FORCEPROP 1 LAST WATTAGE 1/16W
J 2
(-1425 1100);
DISPLAY 0.978723 (-1425 1100);
PAINT SKYBLUE (-1425 1100);
DISPLAY INVISIBLE (-1425 1100);
FORCEPROP 1 LAST TOLERANCE 1%
J 0
(-1400 1150);
DISPLAY 0.978723 (-1400 1150);
PAINT SKYBLUE (-1400 1150);
DISPLAY INVISIBLE (-1400 1150);
FORCEPROP 1 LAST PART_NUMBER TMP_QCS11002FB22
J 0
(-1450 1350);
DISPLAY 0.978723 (-1450 1350);
PAINT SKYBLUE (-1450 1350);
DISPLAY INVISIBLE (-1450 1350);
FORCEPROP 1 LAST PACK_TYPE 0402LF
J 0
(-1150 1100);
DISPLAY 0.978723 (-1150 1100);
PAINT SKYBLUE (-1150 1100);
DISPLAY INVISIBLE (-1150 1100);
FORCEADD Q_RES..1
(-1400 1350);
FORCEPROP 1 LAST LOCATION R1249
J 0
(-1525 1350);
DISPLAY 0.489362 (-1525 1350);
PAINT SKYBLUE (-1525 1350);
FORCEPROP 2 LAST $SEC 1
J 0
(-1450 1550);
DISPLAY 0.680851 (-1450 1550);
PAINT MONO (-1450 1550);
DISPLAY INVISIBLE (-1450 1550);
FORCEPROP 2 LAST CDS_SEC 1
J 0
(-1450 1550);
DISPLAY 0.680851 (-1450 1550);
DISPLAY INVISIBLE (-1450 1550);
FORCEPROP 1 LASTPIN (-1500 1350) $PN 1
J 0
(-1488 1362);
DISPLAY 0.489362 (-1488 1362);
PAINT MONO (-1488 1362);
FORCEPROP 1 LASTPIN (-1300 1350) $PN 2
J 0
(-1338 1362);
DISPLAY 0.489362 (-1338 1362);
PAINT MONO (-1338 1362);
FORCEPROP 1 LAST MATERIAL EMPTY
J 0
(-1250 1350);
DISPLAY 0.489362 (-1250 1350);
PAINT RED (-1250 1350);
FORCEPROP 1 LAST VALUE 100
J 2
(-1275 1350);
DISPLAY 0.489362 (-1275 1350);
PAINT SKYBLUE (-1275 1350);
FORCEPROP 2 LAST CDS_LIB pure_quanta
J 0
(-1400 1350);
DISPLAY INVISIBLE (-1400 1350);
FORCEPROP 1 LAST PATH I251
J 0
(-1450 1500);
DISPLAY 0.978723 (-1450 1500);
PAINT WHITE (-1450 1500);
DISPLAY INVISIBLE (-1450 1500);
FORCEPROP 1 LAST WATTAGE 1/16W
J 2
(-1425 1200);
DISPLAY 0.978723 (-1425 1200);
PAINT SKYBLUE (-1425 1200);
DISPLAY INVISIBLE (-1425 1200);
FORCEPROP 1 LAST TOLERANCE 1%
J 0
(-1400 1250);
DISPLAY 0.978723 (-1400 1250);
PAINT SKYBLUE (-1400 1250);
DISPLAY INVISIBLE (-1400 1250);
FORCEPROP 1 LAST PART_NUMBER TMP_QCS11002FB22
J 0
(-1450 1450);
DISPLAY 0.978723 (-1450 1450);
PAINT SKYBLUE (-1450 1450);
DISPLAY INVISIBLE (-1450 1450);
FORCEPROP 1 LAST PACK_TYPE 0402LF
J 0
(-1150 1200);
DISPLAY 0.978723 (-1150 1200);
PAINT SKYBLUE (-1150 1200);
DISPLAY INVISIBLE (-1150 1200);
FORCEADD UNIVERSAL_GND..1
(-1175 1050);
FORCEPROP 3 LASTPIN (-1175 1100) SIG_NAME GND\g
J 0
(-1165 1110);
DISPLAY 0.659574 (-1165 1110);
PAINT MONO (-1165 1110);
DISPLAY INVISIBLE (-1165 1110);
FORCEPROP 1 LAST HDL_POWER GND
J 1
(-1150 975);
DISPLAY 0.489362 (-1150 975);
PAINT GREEN (-1150 975);
FORCEPROP 2 LAST CDS_LIB pure_quanta_power
J 0
(-1175 1050);
DISPLAY INVISIBLE (-1175 1050);
FORCEPROP 1 LAST PATH I253
J 0
(-1100 1050);
DISPLAY 0.872340 (-1100 1050);
PAINT AQUA (-1100 1050);
DISPLAY INVISIBLE (-1100 1050);
FORCEADD UNIVERSAL_GND..1
(-6250 3025);
FORCEPROP 3 LASTPIN (-6250 3075) SIG_NAME GND\g
J 0
(-6240 3085);
DISPLAY 0.659574 (-6240 3085);
PAINT MONO (-6240 3085);
DISPLAY INVISIBLE (-6240 3085);
FORCEPROP 2 LAST CDS_LIB pure_quanta_power
J 0
(-6250 3025);
DISPLAY INVISIBLE (-6250 3025);
FORCEPROP 1 LAST PATH I254
J 0
(-6175 3025);
DISPLAY 0.872340 (-6175 3025);
PAINT AQUA (-6175 3025);
DISPLAY INVISIBLE (-6175 3025);
FORCEPROP 1 LAST HDL_POWER GND
J 1
(-6225 2950);
DISPLAY 0.872340 (-6225 2950);
PAINT GREEN (-6225 2950);
DISPLAY INVISIBLE (-6225 2950);
FORCEADD Q_RES..2
(-6250 3275);
FORCEPROP 1 LAST LOCATION R1237
J 0
(-6205 3400);
DISPLAY 0.489362 (-6205 3400);
PAINT SKYBLUE (-6205 3400);
FORCEPROP 2 LAST $SEC 1
J 0
(-6200 3500);
DISPLAY 0.680851 (-6200 3500);
PAINT MONO (-6200 3500);
DISPLAY INVISIBLE (-6200 3500);
FORCEPROP 2 LAST CDS_SEC 1
J 0
(-6200 3500);
DISPLAY 1.021277 (-6200 3500);
DISPLAY INVISIBLE (-6200 3500);
FORCEPROP 1 LASTPIN (-6250 3375) $PN 1
J 0
(-6245 3337);
DISPLAY 0.489362 (-6245 3337);
FORCEPROP 1 LASTPIN (-6250 3175) $PN 2
J 0
(-6245 3185);
DISPLAY 0.489362 (-6245 3185);
FORCEPROP 1 LAST WATTAGE 1/16W
J 0
(-6210 3250);
DISPLAY 0.489362 (-6210 3250);
PAINT SKYBLUE (-6210 3250);
FORCEPROP 1 LAST MATERIAL EMPTY
J 0
(-6210 3200);
DISPLAY 0.489362 (-6210 3200);
PAINT RED (-6210 3200);
FORCEPROP 1 LAST TOLERANCE 1%
J 0
(-6205 3300);
DISPLAY 0.489362 (-6205 3300);
PAINT SKYBLUE (-6205 3300);
FORCEPROP 1 LAST VALUE 4.7K
J 0
(-6205 3350);
DISPLAY 0.489362 (-6205 3350);
PAINT SKYBLUE (-6205 3350);
FORCEPROP 1 LAST PACK_TYPE 0402LF
J 0
(-6200 3150);
DISPLAY 0.489362 (-6200 3150);
PAINT SKYBLUE (-6200 3150);
FORCEPROP 2 LAST CDS_LIB pure_quanta
J 0
(-6250 3275);
PAINT MONO (-6250 3275);
DISPLAY INVISIBLE (-6250 3275);
FORCEPROP 1 LAST PATH I255
J 0
(-6200 3450);
DISPLAY 0.978723 (-6200 3450);
PAINT WHITE (-6200 3450);
DISPLAY INVISIBLE (-6200 3450);
FORCEPROP 1 LAST PART_NUMBER CS24702FB10
J 0
(-6210 3150);
DISPLAY 0.617021 (-6210 3150);
PAINT SKYBLUE (-6210 3150);
DISPLAY INVISIBLE (-6210 3150);
FORCEADD Q_RES..2
(-6250 3675);
FORCEPROP 1 LAST LOCATION R1236
J 0
(-6205 3800);
DISPLAY 0.489362 (-6205 3800);
PAINT SKYBLUE (-6205 3800);
FORCEPROP 2 LAST $SEC 1
J 0
(-6200 3900);
DISPLAY 0.680851 (-6200 3900);
PAINT MONO (-6200 3900);
DISPLAY INVISIBLE (-6200 3900);
FORCEPROP 2 LAST CDS_SEC 1
J 0
(-6200 3900);
DISPLAY 1.021277 (-6200 3900);
DISPLAY INVISIBLE (-6200 3900);
FORCEPROP 1 LASTPIN (-6250 3775) $PN 1
J 0
(-6245 3737);
DISPLAY 0.489362 (-6245 3737);
FORCEPROP 1 LASTPIN (-6250 3575) $PN 2
J 0
(-6245 3585);
DISPLAY 0.489362 (-6245 3585);
FORCEPROP 1 LAST WATTAGE 1/16W
J 0
(-6210 3650);
DISPLAY 0.489362 (-6210 3650);
PAINT SKYBLUE (-6210 3650);
FORCEPROP 1 LAST MATERIAL EMPTY
J 0
(-6210 3600);
DISPLAY 0.489362 (-6210 3600);
PAINT RED (-6210 3600);
FORCEPROP 1 LAST TOLERANCE 1%
J 0
(-6205 3700);
DISPLAY 0.489362 (-6205 3700);
PAINT SKYBLUE (-6205 3700);
FORCEPROP 1 LAST VALUE 4.7K
J 0
(-6205 3750);
DISPLAY 0.489362 (-6205 3750);
PAINT SKYBLUE (-6205 3750);
FORCEPROP 1 LAST PACK_TYPE 0402LF
J 0
(-6200 3550);
DISPLAY 0.489362 (-6200 3550);
PAINT SKYBLUE (-6200 3550);
FORCEPROP 2 LAST CDS_LIB pure_quanta
J 0
(-6250 3675);
PAINT MONO (-6250 3675);
DISPLAY INVISIBLE (-6250 3675);
FORCEPROP 1 LAST PATH I256
J 0
(-6200 3850);
DISPLAY 0.978723 (-6200 3850);
PAINT WHITE (-6200 3850);
DISPLAY INVISIBLE (-6200 3850);
FORCEPROP 1 LAST PART_NUMBER CS24702FB10
J 0
(-6210 3550);
DISPLAY 0.617021 (-6210 3550);
PAINT SKYBLUE (-6210 3550);
DISPLAY INVISIBLE (-6210 3550);
FORCEADD UNIVERSAL_POWER..1
(-6250 3925);
FORCEPROP 3 LASTPIN (-6250 3875) SIG_NAME P3V3\g
J 0
(-6240 3885);
DISPLAY 0.659574 (-6240 3885);
PAINT MONO (-6240 3885);
DISPLAY INVISIBLE (-6240 3885);
FORCEPROP 1 LAST HDL_POWER P3V3
J 1
(-6250 3975);
DISPLAY 0.489362 (-6250 3975);
PAINT GREEN (-6250 3975);
FORCEPROP 2 LAST CDS_LIB pure_quanta_power
J 0
(-6250 3925);
DISPLAY INVISIBLE (-6250 3925);
FORCEPROP 1 LAST PATH I257
J 0
(-6200 3950);
DISPLAY 0.872340 (-6200 3950);
PAINT AQUA (-6200 3950);
DISPLAY INVISIBLE (-6200 3950);
FORCEADD Q_RES..2
(-6000 3275);
FORCEPROP 1 LAST LOCATION R1239
J 0
(-5950 3400);
DISPLAY 0.489362 (-5950 3400);
PAINT SKYBLUE (-5950 3400);
FORCEPROP 2 LAST $SEC 1
J 0
(-5950 3500);
DISPLAY 0.680851 (-5950 3500);
PAINT MONO (-5950 3500);
DISPLAY INVISIBLE (-5950 3500);
FORCEPROP 2 LAST CDS_SEC 1
J 0
(-5950 3500);
DISPLAY 0.680851 (-5950 3500);
DISPLAY INVISIBLE (-5950 3500);
FORCEPROP 1 LASTPIN (-6000 3375) $PN 1
J 0
(-5995 3337);
DISPLAY 0.489362 (-5995 3337);
PAINT MONO (-5995 3337);
FORCEPROP 1 LASTPIN (-6000 3175) $PN 2
J 0
(-5995 3185);
DISPLAY 0.489362 (-5995 3185);
PAINT MONO (-5995 3185);
FORCEPROP 1 LAST WATTAGE 1/16W
J 0
(-5960 3250);
DISPLAY 0.489362 (-5960 3250);
PAINT SKYBLUE (-5960 3250);
FORCEPROP 1 LAST MATERIAL EMPTY
J 0
(-5960 3200);
DISPLAY 0.489362 (-5960 3200);
PAINT RED (-5960 3200);
FORCEPROP 1 LAST TOLERANCE 1%
J 0
(-5955 3300);
DISPLAY 0.489362 (-5955 3300);
PAINT SKYBLUE (-5955 3300);
FORCEPROP 1 LAST VALUE 4.7K
J 0
(-5955 3350);
DISPLAY 0.489362 (-5955 3350);
PAINT SKYBLUE (-5955 3350);
FORCEPROP 1 LAST PACK_TYPE 0402LF
J 0
(-5950 3150);
DISPLAY 0.489362 (-5950 3150);
PAINT SKYBLUE (-5950 3150);
FORCEPROP 2 LAST CDS_LIB pure_quanta
J 0
(-6000 3275);
DISPLAY INVISIBLE (-6000 3275);
FORCEPROP 1 LAST PATH I258
J 0
(-5950 3450);
DISPLAY 0.978723 (-5950 3450);
PAINT WHITE (-5950 3450);
DISPLAY INVISIBLE (-5950 3450);
FORCEPROP 1 LAST PART_NUMBER CS24702FB10
J 0
(-5960 3150);
DISPLAY 0.617021 (-5960 3150);
PAINT SKYBLUE (-5960 3150);
DISPLAY INVISIBLE (-5960 3150);
FORCEADD Q_RES..2
(-6000 3675);
FORCEPROP 1 LAST LOCATION R1238
J 0
(-5955 3800);
DISPLAY 0.489362 (-5955 3800);
PAINT SKYBLUE (-5955 3800);
FORCEPROP 2 LAST $SEC 1
J 0
(-5950 3900);
DISPLAY 0.680851 (-5950 3900);
PAINT MONO (-5950 3900);
DISPLAY INVISIBLE (-5950 3900);
FORCEPROP 2 LAST CDS_SEC 1
J 0
(-5950 3900);
DISPLAY 0.680851 (-5950 3900);
DISPLAY INVISIBLE (-5950 3900);
FORCEPROP 1 LASTPIN (-6000 3775) $PN 1
J 0
(-5995 3737);
DISPLAY 0.489362 (-5995 3737);
PAINT MONO (-5995 3737);
FORCEPROP 1 LASTPIN (-6000 3575) $PN 2
J 0
(-5995 3585);
DISPLAY 0.489362 (-5995 3585);
PAINT MONO (-5995 3585);
FORCEPROP 1 LAST WATTAGE 1/16W
J 0
(-5960 3650);
DISPLAY 0.489362 (-5960 3650);
PAINT SKYBLUE (-5960 3650);
FORCEPROP 1 LAST MATERIAL EMPTY
J 0
(-5960 3600);
DISPLAY 0.489362 (-5960 3600);
PAINT RED (-5960 3600);
FORCEPROP 1 LAST TOLERANCE 1%
J 0
(-5955 3700);
DISPLAY 0.489362 (-5955 3700);
PAINT SKYBLUE (-5955 3700);
FORCEPROP 1 LAST VALUE 4.7K
J 0
(-5955 3750);
DISPLAY 0.489362 (-5955 3750);
PAINT SKYBLUE (-5955 3750);
FORCEPROP 1 LAST PACK_TYPE 0402LF
J 0
(-5950 3550);
DISPLAY 0.489362 (-5950 3550);
PAINT SKYBLUE (-5950 3550);
FORCEPROP 2 LAST CDS_LIB pure_quanta
J 0
(-6000 3675);
DISPLAY INVISIBLE (-6000 3675);
FORCEPROP 1 LAST PATH I259
J 0
(-5950 3850);
DISPLAY 0.978723 (-5950 3850);
PAINT WHITE (-5950 3850);
DISPLAY INVISIBLE (-5950 3850);
FORCEPROP 1 LAST PART_NUMBER CS24702FB10
J 0
(-5960 3550);
DISPLAY 0.617021 (-5960 3550);
PAINT SKYBLUE (-5960 3550);
DISPLAY INVISIBLE (-5960 3550);
FORCEADD OFFPAGE..2
(-5050 3425);
FORCEPROP 2 LAST $XR1 112 
J 0
(-4771 3425);
DISPLAY 0.638298 (-4771 3425);
PAINT MONO (-4771 3425);
FORCEPROP 2 LAST $XR0 83 
J 0
(-4861 3425);
DISPLAY 0.638298 (-4861 3425);
PAINT MONO (-4861 3425);
FORCEPROP 1 LAST COMMENT_BODY TRUE
J 0
(-5095 3330);
DISPLAY 0.872340 (-5095 3330);
PAINT GREEN (-5095 3330);
DISPLAY INVISIBLE (-5095 3330);
FORCEPROP 1 LAST OFFPAGE TRUE
J 0
(-4725 3300);
DISPLAY 0.723404 (-4725 3300);
PAINT GREEN (-4725 3300);
DISPLAY INVISIBLE (-4725 3300);
FORCEPROP 2 LAST CDS_LIB standard
J 0
(-5050 3425);
DISPLAY INVISIBLE (-5050 3425);
FORCEPROP 2 LAST PATH I260
J 0
(-4875 3500);
DISPLAY 0.680851 (-4875 3500);
DISPLAY INVISIBLE (-4875 3500);
FORCEADD OFFPAGE..2
(-5050 3500);
FORCEPROP 2 LAST $XR1 112 
J 0
(-4771 3500);
DISPLAY 0.638298 (-4771 3500);
PAINT MONO (-4771 3500);
FORCEPROP 2 LAST $XR0 83 
J 0
(-4861 3500);
DISPLAY 0.638298 (-4861 3500);
PAINT MONO (-4861 3500);
FORCEPROP 2 LAST CDS_LIB standard
J 0
(-5050 3500);
DISPLAY INVISIBLE (-5050 3500);
FORCEPROP 1 LAST OFFPAGE TRUE
J 0
(-4725 3375);
DISPLAY 0.723404 (-4725 3375);
PAINT GREEN (-4725 3375);
DISPLAY INVISIBLE (-4725 3375);
FORCEPROP 1 LAST COMMENT_BODY TRUE
J 0
(-5095 3405);
DISPLAY 0.872340 (-5095 3405);
PAINT GREEN (-5095 3405);
DISPLAY INVISIBLE (-5095 3405);
FORCEPROP 2 LAST PATH I261
J 0
(-4875 3575);
DISPLAY 0.680851 (-4875 3575);
DISPLAY INVISIBLE (-4875 3575);
FORCEADD Q_RES..1
(-4450 1625);
FORCEPROP 1 LAST LOCATION R1241
J 0
(-4650 1625);
DISPLAY 0.489362 (-4650 1625);
PAINT SKYBLUE (-4650 1625);
FORCEPROP 0 LAST $SEC 1
J 0
(-4575 1675);
DISPLAY 0.680851 (-4575 1675);
PAINT MONO (-4575 1675);
DISPLAY INVISIBLE (-4575 1675);
FORCEPROP 0 LAST CDS_SEC 1
J 0
(-4575 1675);
DISPLAY 1.021277 (-4575 1675);
DISPLAY INVISIBLE (-4575 1675);
FORCEPROP 1 LASTPIN (-4550 1625) $PN 1
J 0
(-4538 1637);
DISPLAY 0.489362 (-4538 1637);
PAINT MONO (-4538 1637);
FORCEPROP 1 LASTPIN (-4350 1625) $PN 2
J 0
(-4388 1637);
DISPLAY 0.489362 (-4388 1637);
PAINT MONO (-4388 1637);
FORCEPROP 1 LAST VALUE 0
J 2
(-4325 1625);
DISPLAY 0.489362 (-4325 1625);
PAINT SKYBLUE (-4325 1625);
FORCEPROP 2 LAST CDS_LIB pure_quanta
J 0
(-4450 1625);
DISPLAY INVISIBLE (-4450 1625);
FORCEPROP 1 LAST PATH I262
J 0
(-4500 1775);
DISPLAY 0.978723 (-4500 1775);
PAINT WHITE (-4500 1775);
DISPLAY INVISIBLE (-4500 1775);
FORCEPROP 1 LAST WATTAGE 1/16W
J 2
(-4050 1550);
DISPLAY 0.489362 (-4050 1550);
PAINT SKYBLUE (-4050 1550);
DISPLAY INVISIBLE (-4050 1550);
FORCEPROP 1 LAST MATERIAL CHIP
J 0
(-4025 1550);
DISPLAY 0.489362 (-4025 1550);
PAINT SKYBLUE (-4025 1550);
DISPLAY INVISIBLE (-4025 1550);
FORCEPROP 1 LAST TOLERANCE 5%
J 0
(-4475 1550);
DISPLAY 0.489362 (-4475 1550);
PAINT SKYBLUE (-4475 1550);
DISPLAY INVISIBLE (-4475 1550);
FORCEPROP 1 LAST PART_NUMBER CS00002JB38
J 0
(-4425 1675);
DISPLAY 0.489362 (-4425 1675);
PAINT SKYBLUE (-4425 1675);
DISPLAY INVISIBLE (-4425 1675);
FORCEPROP 1 LAST PACK_TYPE 0402LF
J 0
(-4400 1550);
DISPLAY 0.489362 (-4400 1550);
PAINT SKYBLUE (-4400 1550);
DISPLAY INVISIBLE (-4400 1550);
FORCEADD OFFPAGE..1
(-5250 1625);
FORCEPROP 2 LAST $XR1 112 
J 0
(-5591 1625);
DISPLAY 0.638298 (-5591 1625);
PAINT MONO (-5591 1625);
FORCEPROP 2 LAST $XR0 83 
J 0
(-5471 1625);
DISPLAY 0.638298 (-5471 1625);
PAINT MONO (-5471 1625);
FORCEPROP 2 LAST CDS_LIB standard
J 0
(-5250 1625);
DISPLAY INVISIBLE (-5250 1625);
FORCEPROP 1 LAST OFFPAGE TRUE
J 0
(-4925 1500);
DISPLAY 0.872340 (-4925 1500);
PAINT GREEN (-4925 1500);
DISPLAY INVISIBLE (-4925 1500);
FORCEPROP 1 LAST COMMENT_BODY TRUE
J 0
(-5125 1525);
DISPLAY 0.872340 (-5125 1525);
PAINT GREEN (-5125 1525);
DISPLAY INVISIBLE (-5125 1525);
FORCEPROP 2 LAST PATH I263
J 0
(-5200 1700);
DISPLAY 0.680851 (-5200 1700);
DISPLAY INVISIBLE (-5200 1700);
FORCEADD Q_RES..1
(-4675 4625);
FORCEPROP 1 LAST LOCATION R1240
J 0
(-4875 4625);
DISPLAY 0.489362 (-4875 4625);
PAINT SKYBLUE (-4875 4625);
FORCEPROP 0 LAST $SEC 1
J 0
(-4800 4675);
DISPLAY 0.680851 (-4800 4675);
PAINT MONO (-4800 4675);
DISPLAY INVISIBLE (-4800 4675);
FORCEPROP 0 LAST CDS_SEC 1
J 0
(-4800 4675);
DISPLAY 1.021277 (-4800 4675);
DISPLAY INVISIBLE (-4800 4675);
FORCEPROP 1 LASTPIN (-4775 4625) $PN 1
J 0
(-4763 4637);
DISPLAY 0.489362 (-4763 4637);
PAINT MONO (-4763 4637);
FORCEPROP 1 LASTPIN (-4575 4625) $PN 2
J 0
(-4613 4637);
DISPLAY 0.489362 (-4613 4637);
PAINT MONO (-4613 4637);
FORCEPROP 1 LAST VALUE 0
J 2
(-4550 4625);
DISPLAY 0.489362 (-4550 4625);
PAINT SKYBLUE (-4550 4625);
FORCEPROP 2 LAST CDS_LIB pure_quanta
J 0
(-4675 4625);
DISPLAY INVISIBLE (-4675 4625);
FORCEPROP 1 LAST PATH I264
J 0
(-4725 4775);
DISPLAY 0.978723 (-4725 4775);
PAINT WHITE (-4725 4775);
DISPLAY INVISIBLE (-4725 4775);
FORCEPROP 1 LAST WATTAGE 1/16W
J 2
(-4275 4550);
DISPLAY 0.489362 (-4275 4550);
PAINT SKYBLUE (-4275 4550);
DISPLAY INVISIBLE (-4275 4550);
FORCEPROP 1 LAST MATERIAL CHIP
J 0
(-4250 4550);
DISPLAY 0.489362 (-4250 4550);
PAINT SKYBLUE (-4250 4550);
DISPLAY INVISIBLE (-4250 4550);
FORCEPROP 1 LAST TOLERANCE 5%
J 0
(-4700 4550);
DISPLAY 0.489362 (-4700 4550);
PAINT SKYBLUE (-4700 4550);
DISPLAY INVISIBLE (-4700 4550);
FORCEPROP 1 LAST PART_NUMBER CS00002JB38
J 0
(-4650 4675);
DISPLAY 0.489362 (-4650 4675);
PAINT SKYBLUE (-4650 4675);
DISPLAY INVISIBLE (-4650 4675);
FORCEPROP 1 LAST PACK_TYPE 0402LF
J 0
(-4625 4550);
DISPLAY 0.489362 (-4625 4550);
PAINT SKYBLUE (-4625 4550);
DISPLAY INVISIBLE (-4625 4550);
FORCEADD OFFPAGE..1
(-5475 4625);
FORCEPROP 2 LAST $XR1 112 
J 0
(-5816 4625);
DISPLAY 0.638298 (-5816 4625);
PAINT MONO (-5816 4625);
FORCEPROP 2 LAST $XR0 83 
J 0
(-5696 4625);
DISPLAY 0.638298 (-5696 4625);
PAINT MONO (-5696 4625);
FORCEPROP 2 LAST CDS_LIB standard
J 0
(-5475 4625);
DISPLAY INVISIBLE (-5475 4625);
FORCEPROP 1 LAST OFFPAGE TRUE
J 0
(-5150 4500);
DISPLAY 0.872340 (-5150 4500);
PAINT GREEN (-5150 4500);
DISPLAY INVISIBLE (-5150 4500);
FORCEPROP 1 LAST COMMENT_BODY TRUE
J 0
(-5350 4525);
DISPLAY 0.872340 (-5350 4525);
PAINT GREEN (-5350 4525);
DISPLAY INVISIBLE (-5350 4525);
FORCEPROP 2 LAST PATH I265
J 0
(-5425 4700);
DISPLAY 0.680851 (-5425 4700);
DISPLAY INVISIBLE (-5425 4700);
FORCEADD OFFPAGE..2
(-625 4825);
FORCEPROP 2 LAST $XR0 128 
J 0
(-436 4825);
DISPLAY 0.638298 (-436 4825);
PAINT MONO (-436 4825);
FORCEPROP 2 LAST PATH I266
J 0
(-425 4875);
DISPLAY 0.680851 (-425 4875);
DISPLAY INVISIBLE (-425 4875);
FORCEPROP 1 LAST OFFPAGE TRUE
J 0
(-300 4700);
DISPLAY 0.723404 (-300 4700);
PAINT GREEN (-300 4700);
DISPLAY INVISIBLE (-300 4700);
FORCEPROP 1 LAST COMMENT_BODY TRUE
J 0
(-670 4730);
DISPLAY 0.872340 (-670 4730);
PAINT GREEN (-670 4730);
DISPLAY INVISIBLE (-670 4730);
FORCEPROP 2 LAST CDS_LIB standard
J 0
(-625 4825);
DISPLAY INVISIBLE (-625 4825);
FORCEADD OFFPAGE..2
(-625 4775);
FORCEPROP 2 LAST $XR0 128 
J 0
(-436 4775);
DISPLAY 0.638298 (-436 4775);
PAINT MONO (-436 4775);
FORCEPROP 2 LAST PATH I267
J 0
(-425 4825);
DISPLAY 0.680851 (-425 4825);
DISPLAY INVISIBLE (-425 4825);
FORCEPROP 1 LAST OFFPAGE TRUE
J 0
(-300 4650);
DISPLAY 0.723404 (-300 4650);
PAINT GREEN (-300 4650);
DISPLAY INVISIBLE (-300 4650);
FORCEPROP 1 LAST COMMENT_BODY TRUE
J 0
(-670 4680);
DISPLAY 0.872340 (-670 4680);
PAINT GREEN (-670 4680);
DISPLAY INVISIBLE (-670 4680);
FORCEPROP 2 LAST CDS_LIB standard
J 0
(-625 4775);
DISPLAY INVISIBLE (-625 4775);
FORCEADD Q_RES..1
(-1525 4775);
FORCEPROP 1 LAST LOCATION R2297
J 0
(-1725 4775);
DISPLAY 0.489362 (-1725 4775);
PAINT SKYBLUE (-1725 4775);
FORCEPROP 0 LAST $SEC 1
J 0
(-1600 4825);
DISPLAY 0.680851 (-1600 4825);
PAINT MONO (-1600 4825);
DISPLAY INVISIBLE (-1600 4825);
FORCEPROP 0 LAST CDS_SEC 1
J 0
(-1600 4825);
DISPLAY 1.021277 (-1600 4825);
DISPLAY INVISIBLE (-1600 4825);
FORCEPROP 1 LASTPIN (-1625 4775) $PN 1
J 0
(-1613 4787);
DISPLAY 0.489362 (-1613 4787);
PAINT MONO (-1613 4787);
FORCEPROP 1 LASTPIN (-1425 4775) $PN 2
J 0
(-1463 4787);
DISPLAY 0.489362 (-1463 4787);
PAINT MONO (-1463 4787);
FORCEPROP 1 LAST VALUE 0
J 2
(-1400 4775);
DISPLAY 0.489362 (-1400 4775);
PAINT SKYBLUE (-1400 4775);
FORCEPROP 2 LAST CDS_LIB pure_quanta
J 0
(-1525 4775);
DISPLAY INVISIBLE (-1525 4775);
FORCEPROP 1 LAST PATH I268
J 0
(-1575 4925);
DISPLAY 0.978723 (-1575 4925);
PAINT WHITE (-1575 4925);
DISPLAY INVISIBLE (-1575 4925);
FORCEPROP 1 LAST WATTAGE 1/16W
J 2
(-1125 4700);
DISPLAY 0.489362 (-1125 4700);
PAINT SKYBLUE (-1125 4700);
DISPLAY INVISIBLE (-1125 4700);
FORCEPROP 1 LAST MATERIAL CHIP
J 0
(-1100 4700);
DISPLAY 0.489362 (-1100 4700);
PAINT SKYBLUE (-1100 4700);
DISPLAY INVISIBLE (-1100 4700);
FORCEPROP 1 LAST TOLERANCE 5%
J 0
(-1550 4700);
DISPLAY 0.489362 (-1550 4700);
PAINT SKYBLUE (-1550 4700);
DISPLAY INVISIBLE (-1550 4700);
FORCEPROP 1 LAST PART_NUMBER CS00002JB38
J 0
(-1500 4825);
DISPLAY 0.489362 (-1500 4825);
PAINT SKYBLUE (-1500 4825);
DISPLAY INVISIBLE (-1500 4825);
FORCEPROP 1 LAST PACK_TYPE 0402LF
J 0
(-1475 4700);
DISPLAY 0.489362 (-1475 4700);
PAINT SKYBLUE (-1475 4700);
DISPLAY INVISIBLE (-1475 4700);
FORCEADD Q_RES..1
(-1525 4825);
FORCEPROP 1 LAST LOCATION R2296
J 0
(-1725 4825);
DISPLAY 0.489362 (-1725 4825);
PAINT SKYBLUE (-1725 4825);
FORCEPROP 0 LAST $SEC 1
J 0
(-1600 4875);
DISPLAY 0.680851 (-1600 4875);
PAINT MONO (-1600 4875);
DISPLAY INVISIBLE (-1600 4875);
FORCEPROP 0 LAST CDS_SEC 1
J 0
(-1600 4875);
DISPLAY 1.021277 (-1600 4875);
DISPLAY INVISIBLE (-1600 4875);
FORCEPROP 1 LASTPIN (-1625 4825) $PN 1
J 0
(-1613 4837);
DISPLAY 0.489362 (-1613 4837);
PAINT MONO (-1613 4837);
FORCEPROP 1 LASTPIN (-1425 4825) $PN 2
J 0
(-1463 4837);
DISPLAY 0.489362 (-1463 4837);
PAINT MONO (-1463 4837);
FORCEPROP 1 LAST VALUE 0
J 2
(-1400 4825);
DISPLAY 0.489362 (-1400 4825);
PAINT SKYBLUE (-1400 4825);
FORCEPROP 2 LAST CDS_LIB pure_quanta
J 0
(-1525 4825);
DISPLAY INVISIBLE (-1525 4825);
FORCEPROP 1 LAST PATH I269
J 0
(-1575 4975);
DISPLAY 0.978723 (-1575 4975);
PAINT WHITE (-1575 4975);
DISPLAY INVISIBLE (-1575 4975);
FORCEPROP 1 LAST WATTAGE 1/16W
J 2
(-1125 4750);
DISPLAY 0.489362 (-1125 4750);
PAINT SKYBLUE (-1125 4750);
DISPLAY INVISIBLE (-1125 4750);
FORCEPROP 1 LAST MATERIAL CHIP
J 0
(-1100 4750);
DISPLAY 0.489362 (-1100 4750);
PAINT SKYBLUE (-1100 4750);
DISPLAY INVISIBLE (-1100 4750);
FORCEPROP 1 LAST TOLERANCE 5%
J 0
(-1550 4750);
DISPLAY 0.489362 (-1550 4750);
PAINT SKYBLUE (-1550 4750);
DISPLAY INVISIBLE (-1550 4750);
FORCEPROP 1 LAST PART_NUMBER CS00002JB38
J 0
(-1500 4875);
DISPLAY 0.489362 (-1500 4875);
PAINT SKYBLUE (-1500 4875);
DISPLAY INVISIBLE (-1500 4875);
FORCEPROP 1 LAST PACK_TYPE 0402LF
J 0
(-1475 4750);
DISPLAY 0.489362 (-1475 4750);
PAINT SKYBLUE (-1475 4750);
DISPLAY INVISIBLE (-1475 4750);
FORCEADD Q_RES..1
(-1475 3875);
FORCEPROP 1 LAST LOCATION R1234
J 0
(-1700 3875);
DISPLAY 0.489362 (-1700 3875);
PAINT SKYBLUE (-1700 3875);
FORCEPROP 2 LAST $SEC 1
J 0
(-1525 4075);
DISPLAY 0.680851 (-1525 4075);
PAINT MONO (-1525 4075);
DISPLAY INVISIBLE (-1525 4075);
FORCEPROP 2 LAST CDS_SEC 1
J 0
(-1525 4075);
DISPLAY 0.680851 (-1525 4075);
DISPLAY INVISIBLE (-1525 4075);
FORCEPROP 1 LASTPIN (-1575 3875) $PN 1
J 0
(-1563 3887);
DISPLAY 0.489362 (-1563 3887);
PAINT MONO (-1563 3887);
FORCEPROP 1 LASTPIN (-1375 3875) $PN 2
J 0
(-1413 3887);
DISPLAY 0.489362 (-1413 3887);
PAINT MONO (-1413 3887);
FORCEPROP 1 LAST MATERIAL EMPTY
J 0
(-1325 3875);
DISPLAY 0.489362 (-1325 3875);
PAINT RED (-1325 3875);
FORCEPROP 1 LAST VALUE 100
J 2
(-1350 3875);
DISPLAY 0.489362 (-1350 3875);
PAINT SKYBLUE (-1350 3875);
FORCEPROP 2 LAST CDS_LIB pure_quanta
J 0
(-1475 3875);
DISPLAY INVISIBLE (-1475 3875);
FORCEPROP 1 LAST PATH I270
J 0
(-1525 4025);
DISPLAY 0.978723 (-1525 4025);
PAINT WHITE (-1525 4025);
DISPLAY INVISIBLE (-1525 4025);
FORCEPROP 1 LAST WATTAGE 1/16W
J 2
(-1500 3725);
DISPLAY 0.978723 (-1500 3725);
PAINT SKYBLUE (-1500 3725);
DISPLAY INVISIBLE (-1500 3725);
FORCEPROP 1 LAST TOLERANCE 1%
J 0
(-1475 3775);
DISPLAY 0.978723 (-1475 3775);
PAINT SKYBLUE (-1475 3775);
DISPLAY INVISIBLE (-1475 3775);
FORCEPROP 1 LAST PART_NUMBER TMP_QCS11002FB22
J 0
(-1525 3975);
DISPLAY 0.978723 (-1525 3975);
PAINT SKYBLUE (-1525 3975);
DISPLAY INVISIBLE (-1525 3975);
FORCEPROP 1 LAST PACK_TYPE 0402LF
J 0
(-1225 3725);
DISPLAY 0.978723 (-1225 3725);
PAINT SKYBLUE (-1225 3725);
DISPLAY INVISIBLE (-1225 3725);
FORCEADD OFFPAGE..4
(-625 4425);
FORCEPROP 2 LAST $XR0 79 
J 0
(-439 4425);
DISPLAY 0.638298 (-439 4425);
PAINT MONO (-439 4425);
FORCEPROP 2 LAST PATH I272
J 0
(-425 4475);
DISPLAY 0.680851 (-425 4475);
DISPLAY INVISIBLE (-425 4475);
FORCEPROP 1 LAST OFFPAGE TRUE
J 0
(-300 4300);
DISPLAY 0.872340 (-300 4300);
PAINT GREEN (-300 4300);
DISPLAY INVISIBLE (-300 4300);
FORCEPROP 1 LAST COMMENT_BODY TRUE
J 0
(-650 4325);
DISPLAY 0.872340 (-650 4325);
PAINT GREEN (-650 4325);
DISPLAY INVISIBLE (-650 4325);
FORCEPROP 2 LAST CDS_LIB standard
J 0
(-625 4425);
DISPLAY INVISIBLE (-625 4425);
FORCEADD VCC_CORE..1
(-4450 5425);
FORCEPROP 3 LASTPIN (-4450 5375) SIG_NAME P3V3_9ZX_VDDA_3\g
J 0
(-4440 5385);
DISPLAY 0.659574 (-4440 5385);
PAINT MONO (-4440 5385);
DISPLAY INVISIBLE (-4440 5385);
FORCEPROP 1 LAST HDL_POWER P3V3_9ZX_VDDA_3
J 1
(-4450 5475);
DISPLAY 0.489362 (-4450 5475);
PAINT GREEN (-4450 5475);
FORCEPROP 2 LAST BOM_COST SYS_CLOCK
J 0
(-4450 5575);
DISPLAY 0.808511 (-4450 5575);
DISPLAY INVISIBLE (-4450 5575);
FORCEPROP 2 LAST CDS_LIB pure_quanta_power
J 0
(-4450 5425);
DISPLAY INVISIBLE (-4450 5425);
FORCEPROP 1 LAST PATH I3
J 0
(-4400 5450);
DISPLAY 0.872340 (-4400 5450);
PAINT AQUA (-4400 5450);
DISPLAY INVISIBLE (-4400 5450);
FORCEPROP 0 LAST VOLTAGE 3.3
J 0
(-4450 5575);
DISPLAY 1.021277 (-4450 5575);
PAINT SKYBLUE (-4450 5575);
DISPLAY INVISIBLE (-4450 5575);
FORCEPROP 2 LAST ROOM DB2000_1_BCLK
J 0
(-4450 5525);
DISPLAY 0.808511 (-4450 5525);
PAINT RED (-4450 5525);
DISPLAY INVISIBLE (-4450 5525);
FORCEADD UNIVERSAL_POWER..1
(-4050 5800);
FORCEPROP 3 LASTPIN (-4050 5750) SIG_NAME P3V3_9ZX_VDD_3\g
J 0
(-4040 5760);
DISPLAY 0.659574 (-4040 5760);
PAINT MONO (-4040 5760);
DISPLAY INVISIBLE (-4040 5760);
FORCEPROP 1 LAST HDL_POWER P3V3_9ZX_VDD_3
J 1
(-4050 5850);
DISPLAY 0.489362 (-4050 5850);
PAINT GREEN (-4050 5850);
FORCEPROP 2 LAST BOM_COST SYS_CLOCK
J 0
(-4050 5950);
DISPLAY 0.808511 (-4050 5950);
DISPLAY INVISIBLE (-4050 5950);
FORCEPROP 2 LAST CDS_LIB pure_quanta_power
J 0
(-4050 5800);
DISPLAY INVISIBLE (-4050 5800);
FORCEPROP 1 LAST PATH I4
J 0
(-4000 5825);
DISPLAY 0.872340 (-4000 5825);
PAINT AQUA (-4000 5825);
DISPLAY INVISIBLE (-4000 5825);
FORCEPROP 0 LAST VOLTAGE 3.3
J 0
(-4050 5950);
DISPLAY 1.021277 (-4050 5950);
PAINT SKYBLUE (-4050 5950);
DISPLAY INVISIBLE (-4050 5950);
FORCEPROP 2 LAST ROOM DB2000_1_BCLK
J 0
(-4050 5900);
DISPLAY 0.808511 (-4050 5900);
PAINT RED (-4050 5900);
DISPLAY INVISIBLE (-4050 5900);
FORCEADD VCC_CORE..1
(-2450 5800);
FORCEPROP 3 LASTPIN (-2450 5750) SIG_NAME P3V3_9ZX_VDDA_3\g
J 0
(-2440 5760);
DISPLAY 0.659574 (-2440 5760);
PAINT MONO (-2440 5760);
DISPLAY INVISIBLE (-2440 5760);
FORCEPROP 1 LAST HDL_POWER P3V3_9ZX_VDDA_3
J 1
(-2450 5850);
DISPLAY 0.489362 (-2450 5850);
PAINT GREEN (-2450 5850);
FORCEPROP 2 LAST BOM_COST SYS_CLOCK
J 0
(-2450 5950);
DISPLAY 0.808511 (-2450 5950);
DISPLAY INVISIBLE (-2450 5950);
FORCEPROP 2 LAST CDS_LIB pure_quanta_power
J 0
(-2450 5800);
DISPLAY INVISIBLE (-2450 5800);
FORCEPROP 1 LAST PATH I5
J 0
(-2400 5825);
DISPLAY 0.872340 (-2400 5825);
PAINT AQUA (-2400 5825);
DISPLAY INVISIBLE (-2400 5825);
FORCEPROP 0 LAST VOLTAGE 3.3
J 0
(-2450 5950);
DISPLAY 1.021277 (-2450 5950);
PAINT SKYBLUE (-2450 5950);
DISPLAY INVISIBLE (-2450 5950);
FORCEPROP 2 LAST ROOM DB2000_1_BCLK
J 0
(-2450 5900);
DISPLAY 0.808511 (-2450 5900);
PAINT RED (-2450 5900);
DISPLAY INVISIBLE (-2450 5900);
FORCEADD VCC_CORE..1
(-4500 2350);
FORCEPROP 3 LASTPIN (-4500 2300) SIG_NAME P3V3_9ZX_VDDA_4\g
J 0
(-4490 2310);
DISPLAY 0.659574 (-4490 2310);
PAINT MONO (-4490 2310);
DISPLAY INVISIBLE (-4490 2310);
FORCEPROP 1 LAST HDL_POWER P3V3_9ZX_VDDA_4
J 1
(-4500 2400);
DISPLAY 0.489362 (-4500 2400);
PAINT GREEN (-4500 2400);
FORCEPROP 2 LAST CDS_LIB pure_quanta_power
J 0
(-4500 2350);
DISPLAY INVISIBLE (-4500 2350);
FORCEPROP 2 LAST BOM_COST SYS_CLOCK
J 0
(-4500 2500);
DISPLAY 0.808511 (-4500 2500);
DISPLAY INVISIBLE (-4500 2500);
FORCEPROP 1 LAST PATH I6
J 0
(-4450 2375);
DISPLAY 0.872340 (-4450 2375);
PAINT AQUA (-4450 2375);
DISPLAY INVISIBLE (-4450 2375);
FORCEPROP 0 LAST VOLTAGE 3.3
J 0
(-4500 2500);
DISPLAY 1.021277 (-4500 2500);
PAINT SKYBLUE (-4500 2500);
DISPLAY INVISIBLE (-4500 2500);
FORCEPROP 2 LAST ROOM DB2000_1_BCLK
J 0
(-4500 2450);
DISPLAY 0.808511 (-4500 2450);
PAINT RED (-4500 2450);
DISPLAY INVISIBLE (-4500 2450);
FORCEADD UNIVERSAL_POWER..1
(-4100 2725);
FORCEPROP 3 LASTPIN (-4100 2675) SIG_NAME P3V3_9ZX_VDD_4\g
J 0
(-4090 2685);
DISPLAY 0.659574 (-4090 2685);
PAINT MONO (-4090 2685);
DISPLAY INVISIBLE (-4090 2685);
FORCEPROP 1 LAST HDL_POWER P3V3_9ZX_VDD_4
J 1
(-4100 2775);
DISPLAY 0.489362 (-4100 2775);
PAINT GREEN (-4100 2775);
FORCEPROP 2 LAST CDS_LIB pure_quanta_power
J 0
(-4100 2725);
DISPLAY INVISIBLE (-4100 2725);
FORCEPROP 2 LAST BOM_COST SYS_CLOCK
J 0
(-4100 2875);
DISPLAY 0.808511 (-4100 2875);
DISPLAY INVISIBLE (-4100 2875);
FORCEPROP 1 LAST PATH I7
J 0
(-4050 2750);
DISPLAY 0.872340 (-4050 2750);
PAINT AQUA (-4050 2750);
DISPLAY INVISIBLE (-4050 2750);
FORCEPROP 0 LAST VOLTAGE 3.3
J 0
(-4100 2875);
DISPLAY 1.021277 (-4100 2875);
PAINT SKYBLUE (-4100 2875);
DISPLAY INVISIBLE (-4100 2875);
FORCEPROP 2 LAST ROOM DB2000_1_BCLK
J 0
(-4100 2825);
DISPLAY 0.808511 (-4100 2825);
PAINT RED (-4100 2825);
DISPLAY INVISIBLE (-4100 2825);
FORCEADD OFFPAGE..1
(-4675 4975);
FORCEPROP 2 LAST $XR0 28 
J 0
(-4896 4975);
DISPLAY 0.638298 (-4896 4975);
PAINT MONO (-4896 4975);
FORCEPROP 2 LAST CDS_LIB standard
J 0
(-4675 4975);
DISPLAY INVISIBLE (-4675 4975);
FORCEPROP 2 LAST PATH I77
J 0
(-4625 5050);
DISPLAY 1.021277 (-4625 5050);
DISPLAY INVISIBLE (-4625 5050);
FORCEPROP 1 LAST OFFPAGE TRUE
J 0
(-4350 4850);
DISPLAY 0.872340 (-4350 4850);
PAINT GREEN (-4350 4850);
DISPLAY INVISIBLE (-4350 4850);
FORCEPROP 1 LAST COMMENT_BODY TRUE
J 0
(-4550 4875);
DISPLAY 0.872340 (-4550 4875);
PAINT GREEN (-4550 4875);
DISPLAY INVISIBLE (-4550 4875);
FORCEADD OFFPAGE..1
(-4675 5025);
FORCEPROP 2 LAST $XR0 28 
J 0
(-4896 5025);
DISPLAY 0.638298 (-4896 5025);
PAINT MONO (-4896 5025);
FORCEPROP 2 LAST CDS_LIB standard
J 0
(-4675 5025);
DISPLAY INVISIBLE (-4675 5025);
FORCEPROP 2 LAST PATH I78
J 0
(-4625 5100);
DISPLAY 1.021277 (-4625 5100);
DISPLAY INVISIBLE (-4625 5100);
FORCEPROP 1 LAST OFFPAGE TRUE
J 0
(-4350 4900);
DISPLAY 0.872340 (-4350 4900);
PAINT GREEN (-4350 4900);
DISPLAY INVISIBLE (-4350 4900);
FORCEPROP 1 LAST COMMENT_BODY TRUE
J 0
(-4550 4925);
DISPLAY 0.872340 (-4550 4925);
PAINT GREEN (-4550 4925);
DISPLAY INVISIBLE (-4550 4925);
FORCEADD VCC_CORE..1
(-2250 2750);
FORCEPROP 3 LASTPIN (-2250 2700) SIG_NAME P3V3_9ZX_VDDA_4\g
J 0
(-2240 2710);
DISPLAY 0.659574 (-2240 2710);
PAINT MONO (-2240 2710);
DISPLAY INVISIBLE (-2240 2710);
FORCEPROP 1 LAST HDL_POWER P3V3_9ZX_VDDA_4
J 1
(-2250 2800);
DISPLAY 0.489362 (-2250 2800);
PAINT GREEN (-2250 2800);
FORCEPROP 2 LAST BOM_COST SYS_CLOCK
J 0
(-2250 2900);
DISPLAY 0.808511 (-2250 2900);
DISPLAY INVISIBLE (-2250 2900);
FORCEPROP 2 LAST CDS_LIB pure_quanta_power
J 0
(-2250 2750);
DISPLAY INVISIBLE (-2250 2750);
FORCEPROP 1 LAST PATH I8
J 0
(-2200 2775);
DISPLAY 0.872340 (-2200 2775);
PAINT AQUA (-2200 2775);
DISPLAY INVISIBLE (-2200 2775);
FORCEPROP 0 LAST VOLTAGE 3.3
J 0
(-2250 2900);
DISPLAY 1.021277 (-2250 2900);
PAINT SKYBLUE (-2250 2900);
DISPLAY INVISIBLE (-2250 2900);
FORCEPROP 2 LAST ROOM DB2000_1_BCLK
J 0
(-2250 2850);
DISPLAY 0.808511 (-2250 2850);
PAINT RED (-2250 2850);
DISPLAY INVISIBLE (-2250 2850);
FORCEADD Q_RES..1
(-1525 5075);
FORCEPROP 1 LAST LOCATION R2305
J 0
(-1750 5075);
DISPLAY 0.489362 (-1750 5075);
PAINT SKYBLUE (-1750 5075);
FORCEPROP 0 LAST $SEC 1
J 0
(-1600 5125);
DISPLAY 0.680851 (-1600 5125);
PAINT MONO (-1600 5125);
DISPLAY INVISIBLE (-1600 5125);
FORCEPROP 0 LAST CDS_SEC 1
J 0
(-1600 5125);
DISPLAY 1.021277 (-1600 5125);
DISPLAY INVISIBLE (-1600 5125);
FORCEPROP 1 LASTPIN (-1625 5075) $PN 1
J 0
(-1613 5087);
DISPLAY 0.489362 (-1613 5087);
PAINT MONO (-1613 5087);
FORCEPROP 1 LASTPIN (-1425 5075) $PN 2
J 0
(-1463 5087);
DISPLAY 0.489362 (-1463 5087);
PAINT MONO (-1463 5087);
FORCEPROP 1 LAST VALUE 0
J 2
(-1400 5075);
DISPLAY 0.489362 (-1400 5075);
PAINT SKYBLUE (-1400 5075);
FORCEPROP 2 LAST CDS_LIB pure_quanta
J 0
(-1525 5075);
DISPLAY INVISIBLE (-1525 5075);
FORCEPROP 1 LAST PATH I99
J 0
(-1575 5225);
DISPLAY 0.978723 (-1575 5225);
PAINT WHITE (-1575 5225);
DISPLAY INVISIBLE (-1575 5225);
FORCEPROP 1 LAST WATTAGE 1/16W
J 2
(-1125 5000);
DISPLAY 0.489362 (-1125 5000);
PAINT SKYBLUE (-1125 5000);
DISPLAY INVISIBLE (-1125 5000);
FORCEPROP 1 LAST MATERIAL CHIP
J 0
(-1100 5000);
DISPLAY 0.489362 (-1100 5000);
PAINT SKYBLUE (-1100 5000);
DISPLAY INVISIBLE (-1100 5000);
FORCEPROP 1 LAST TOLERANCE 5%
J 0
(-1550 5000);
DISPLAY 0.489362 (-1550 5000);
PAINT SKYBLUE (-1550 5000);
DISPLAY INVISIBLE (-1550 5000);
FORCEPROP 1 LAST PART_NUMBER CS00002JB38
J 0
(-1500 5125);
DISPLAY 0.489362 (-1500 5125);
PAINT SKYBLUE (-1500 5125);
DISPLAY INVISIBLE (-1500 5125);
FORCEPROP 1 LAST PACK_TYPE 0402LF
J 0
(-1475 5000);
DISPLAY 0.489362 (-1475 5000);
PAINT SKYBLUE (-1475 5000);
DISPLAY INVISIBLE (-1475 5000);
FORCEADD DNS..2
(-1375 4175);
PAINT RED (-1375 4175);
FORCEPROP 2 LAST CDS_LIB mstr_misc
J 0
(-1375 4175);
DISPLAY INVISIBLE (-1375 4175);
FORCEPROP 1 LAST COMMENT_BODY TRUE
J 0
(-1375 4175);
DISPLAY INVISIBLE (-1375 4175);
FORCEADD DESIGN_NOTE..1
(-3325 3925);
FORCEPROP 0 LAST L1 ADDRESS : 6D/DA
J 0
(-3525 3800);
DISPLAY 1.276596 (-3525 3800);
FORCEPROP 2 LAST CDS_LIB pure_quanta_power
J 0
(-3325 3925);
DISPLAY INVISIBLE (-3325 3925);
FORCEPROP 1 LAST COMMENT_BODY TRUE
J 0
(-3300 4025);
DISPLAY 0.978723 (-3300 4025);
DISPLAY INVISIBLE (-3300 4025);
FORCEADD DNS..2
(-6000 3700);
PAINT RED (-6000 3700);
FORCEPROP 2 LAST CDS_LIB mstr_misc
J 0
(-6000 3700);
DISPLAY INVISIBLE (-6000 3700);
FORCEPROP 1 LAST COMMENT_BODY TRUE
J 0
(-6000 3700);
DISPLAY INVISIBLE (-6000 3700);
FORCEADD DNS..2
(-6025 3325);
PAINT RED (-6025 3325);
FORCEPROP 2 LAST CDS_LIB mstr_misc
J 0
(-6025 3325);
DISPLAY INVISIBLE (-6025 3325);
FORCEPROP 1 LAST COMMENT_BODY TRUE
J 0
(-6025 3325);
DISPLAY INVISIBLE (-6025 3325);
FORCEADD DNS..2
(-1400 1375);
PAINT RED (-1400 1375);
FORCEPROP 2 LAST CDS_LIB mstr_misc
J 0
(-1400 1375);
DISPLAY INVISIBLE (-1400 1375);
FORCEPROP 1 LAST COMMENT_BODY TRUE
J 0
(-1400 1375);
DISPLAY INVISIBLE (-1400 1375);
FORCEADD DNS..2
(-1400 4075);
PAINT RED (-1400 4075);
FORCEPROP 2 LAST CDS_LIB mstr_misc
J 0
(-1400 4075);
DISPLAY INVISIBLE (-1400 4075);
FORCEPROP 1 LAST COMMENT_BODY TRUE
J 0
(-1400 4075);
DISPLAY INVISIBLE (-1400 4075);
FORCEADD DNS..2
(-8225 3250);
PAINT RED (-8225 3250);
FORCEPROP 2 LAST CDS_LIB mstr_misc
J 0
(-8225 3250);
DISPLAY INVISIBLE (-8225 3250);
FORCEPROP 1 LAST COMMENT_BODY TRUE
J 0
(-8225 3250);
DISPLAY INVISIBLE (-8225 3250);
FORCEADD DESIGN_NOTE..1
(-3325 875);
FORCEPROP 0 LAST L1 ADDRESS : 6F/DE
J 0
(-3525 750);
DISPLAY 1.276596 (-3525 750);
FORCEPROP 2 LAST CDS_LIB pure_quanta_power
J 0
(-3325 875);
DISPLAY INVISIBLE (-3325 875);
FORCEPROP 1 LAST COMMENT_BODY TRUE
J 0
(-3300 975);
DISPLAY 0.978723 (-3300 975);
DISPLAY INVISIBLE (-3300 975);
FORCEADD QUANTA_TITLE_BLOCK_C..1
(-100 100);
FORCEPROP 0 LAST CDS_CON_LAST_MODIFIED Fri Mar 11 14:53:12 2022
J 0
(-1985 115);
DISPLAY INVISIBLE (-1985 115);
FORCEPROP 1 LAST CUSTOM_TXT_CDS <CON_LAST_MODIFIED>
J 0
(-1985 115);
DISPLAY 0.978723 (-1985 115);
FORCEPROP 2 LAST CUSTOM_TXT_CDS <XR_PAGE_TITLE>
J 0
(-7990 5350);
DISPLAY 0.638298 (-7990 5350);
PAINT PINK (-7990 5350);
DISPLAY INVISIBLE (-7990 5350);
FORCEPROP 1 LAST CUSTOM_TXT_CDS <NAME_2>
J 0
(-3275 150);
FORCEPROP 1 LAST CUSTOM_TXT_CDS <NAME_1>
J 0
(-3275 275);
FORCEPROP 1 LAST CUSTOM_TXT_CDS <Q_NUMBER>
J 0
(-1503 203);
DISPLAY 1.212766 (-1503 203);
FORCEPROP 1 LAST CUSTOM_TXT_CDS <Q_PROJ>
J 0
(-2482 202);
DISPLAY 1.212766 (-2482 202);
FORCEPROP 1 LAST CUSTOM_TXT_CDS <Q_REV>
J 0
(-284 203);
DISPLAY 1.212766 (-284 203);
FORCEPROP 1 LAST CUSTOM_TXT_CDS <CON_PAGE_NUM> OF <CON_TOTAL_PAGES>
J 0
(-546 118);
DISPLAY 0.978723 (-546 118);
FORCEPROP 1 LAST Q_TITLE CLK BUF - E1.S/M.2 CONN
J 0
(-9375 175);
DISPLAY 2.446809 (-9375 175);
PAINT GREEN (-9375 175);
FORCEPROP 1 LAST Q_DEPT BU9
J 1
(-3863 149);
DISPLAY 1.957447 (-3863 149);
PAINT GREEN (-3863 149);
FORCEPROP 2 LAST CDS_LIB pure_quanta
J 0
(-100 100);
DISPLAY INVISIBLE (-100 100);
FORCEPROP 1 LAST CDS_LMAN_SYM_OUTLINE -9475,6775,100,-125
J 0
(-100 100);
DISPLAY 0.468085 (-100 100);
PAINT GREEN (-100 100);
DISPLAY INVISIBLE (-100 100);
FORCEPROP 2 LAST PAGE_BORDER TRUE
J 0
(-7990 5350);
DISPLAY 0.638298 (-7990 5350);
PAINT PINK (-7990 5350);
DISPLAY INVISIBLE (-7990 5350);
FORCEPROP 1 LAST COMMENT_BODY TRUE
J 0
(-88 87);
DISPLAY 0.978723 (-88 87);
PAINT GREEN (-88 87);
DISPLAY INVISIBLE (-88 87);
FORCEPROP 2 LAST CDS_XR_PAGE_TITLE CR-112 : @T6G_MB_LIB.T6G(SCH_1):PAGE112
J 0
(-7990 5350);
DISPLAY 0.638298 (-7990 5350);
PAINT PINK (-7990 5350);
DISPLAY INVISIBLE (-7990 5350);
FORCEADD DNS..2
(-6275 3300);
PAINT RED (-6275 3300);
FORCEPROP 2 LAST CDS_LIB mstr_misc
J 0
(-6275 3300);
DISPLAY INVISIBLE (-6275 3300);
FORCEPROP 1 LAST COMMENT_BODY TRUE
J 0
(-6275 3300);
DISPLAY INVISIBLE (-6275 3300);
FORCEADD DNS..2
(-1375 3950);
PAINT RED (-1375 3950);
FORCEPROP 2 LAST CDS_LIB mstr_misc
J 0
(-1375 3950);
DISPLAY INVISIBLE (-1375 3950);
FORCEPROP 1 LAST COMMENT_BODY TRUE
J 0
(-1375 3950);
DISPLAY INVISIBLE (-1375 3950);
FORCEADD DNS..2
(-6275 3675);
PAINT RED (-6275 3675);
FORCEPROP 2 LAST CDS_LIB mstr_misc
J 0
(-6275 3675);
DISPLAY INVISIBLE (-6275 3675);
FORCEPROP 1 LAST COMMENT_BODY TRUE
J 0
(-6275 3675);
DISPLAY INVISIBLE (-6275 3675);
FORCEADD DNS..2
(-1375 3800);
PAINT RED (-1375 3800);
FORCEPROP 2 LAST CDS_LIB mstr_misc
J 0
(-1375 3800);
DISPLAY INVISIBLE (-1375 3800);
FORCEPROP 1 LAST COMMENT_BODY TRUE
J 0
(-1375 3800);
DISPLAY INVISIBLE (-1375 3800);
WIRE 16 -1 (-8325 1460)(-8325 1325);
WIRE 16 -1 (-7925 1425)(-7925 1300);
WIRE 16 -1 (-7675 1425)(-7675 1300);
WIRE 16 -1 (-7450 1425)(-7450 1300);
WIRE 16 -1 (-7220 1420)(-7220 1295);
WIRE 16 -1 (-6990 1415)(-6990 1290);
WIRE 16 -1 (-8500 4685)(-8500 4550);
WIRE 16 -1 (-8100 4650)(-8100 4525);
WIRE 16 -1 (-7850 4650)(-7850 4525);
WIRE 16 -1 (-7625 4650)(-7625 4525);
WIRE 16 -1 (-7395 4645)(-7395 4520);
WIRE 16 -1 (-7165 4640)(-7165 4515);
WIRE 16 -1 (-6325 1950)(-6325 1825);
WIRE 16 -1 (-6075 1950)(-6075 1825);
WIRE 16 -1 (-5875 1950)(-5875 1825);
WIRE 16 -1 (-6200 5175)(-6200 5050);
WIRE 16 -1 (-5950 5175)(-5950 5050);
WIRE 16 -1 (-5750 5175)(-5750 5050);
WIRE 16 -1 (-1550 5925)(-1550 5875);
WIRE 16 -1 (-1525 2850)(-1525 2800);
WIRE 16 -1 (-2500 4225)(-2575 4225);
WIRE 16 -1 (-2500 4225)(-2500 4075);
WIRE 16 -1 (-8525 3775)(-8525 3875);
WIRE 16 -1 (-8525 3150)(-8525 3125);
WIRE 16 -1 (-8275 3775)(-8275 3875);
WIRE 16 -1 (-8275 3150)(-8275 3125);
WIRE 16 -1 (-8850 2300)(-8850 2200);
WIRE 16 -1 (-8850 2200)(-8600 2200);
WIRE 16 -1 (-9025 5525)(-9025 5425);
WIRE 16 -1 (-9025 5425)(-8775 5425);
WIRE 16 -1 (-7350 5575)(-7350 5425);
WIRE 16 -1 (-7350 5425)(-7100 5425);
WIRE 16 -1 (-7350 5425)(-8500 5425);
WIRE 16 -1 (-8500 5425)(-8575 5425);
WIRE 16 -1 (-8500 5425)(-8500 4925);
WIRE 16 -1 (-8100 4925)(-8500 4925);
WIRE 16 -1 (-8500 4925)(-8500 4885);
WIRE 16 -1 (-8100 4925)(-7850 4925);
WIRE 16 -1 (-8100 4850)(-8100 4925);
WIRE 16 -1 (-7850 4925)(-7625 4925);
WIRE 16 -1 (-7850 4850)(-7850 4925);
WIRE 16 -1 (-7625 4925)(-7395 4925);
WIRE 16 -1 (-7625 4925)(-7625 4850);
WIRE 16 -1 (-7395 4925)(-7165 4925);
WIRE 16 -1 (-7395 4845)(-7395 4925);
WIRE 16 -1 (-7165 4925)(-7165 4840);
WIRE 16 -1 (-7175 2350)(-7175 2200);
WIRE 16 -1 (-7175 2200)(-6925 2200);
WIRE 16 -1 (-7175 2200)(-8325 2200);
WIRE 16 -1 (-8325 2200)(-8400 2200);
WIRE 16 -1 (-8325 2200)(-8325 1700);
WIRE 16 -1 (-7925 1700)(-8325 1700);
WIRE 16 -1 (-8325 1700)(-8325 1660);
WIRE 16 -1 (-7925 1700)(-7675 1700);
WIRE 16 -1 (-7925 1625)(-7925 1700);
WIRE 16 -1 (-7675 1700)(-7450 1700);
WIRE 16 -1 (-7675 1625)(-7675 1700);
WIRE 16 -1 (-7450 1700)(-7220 1700);
WIRE 16 -1 (-7450 1700)(-7450 1625);
WIRE 16 -1 (-7220 1700)(-6990 1700);
WIRE 16 -1 (-7220 1620)(-7220 1700);
WIRE 16 -1 (-6990 1700)(-6990 1615);
WIRE 16 -1 (-8525 3525)(-7475 3525);
FORCEPROP 2 LAST SIG_NAME SADR_3
J 0
(-7710 3535);
DISPLAY 0.489362 (-7710 3535);
WIRE 16 -1 (-8525 3525)(-8525 3350);
WIRE 16 -1 (-8525 3575)(-8525 3525);
WIRE 16 -1 (-7475 3450)(-8275 3450);
FORCEPROP 2 LAST SIG_NAME SADR_4
J 0
(-7710 3460);
DISPLAY 0.489362 (-7710 3460);
WIRE 16 -1 (-8275 3575)(-8275 3450);
WIRE 16 -1 (-8275 3450)(-8275 3350);
WIRE 16 -1 (-6250 3850)(-6000 3850);
WIRE 16 -1 (-6250 3850)(-6250 3875);
WIRE 16 -1 (-6250 3775)(-6250 3850);
WIRE 16 -1 (-6000 3850)(-6000 3775);
WIRE 16 -1 (-6000 3125)(-6250 3125);
WIRE 16 -1 (-6000 3175)(-6000 3125);
WIRE 16 -1 (-6250 3125)(-6250 3075);
WIRE 16 -1 (-6250 3175)(-6250 3125);
WIRE 16 -1 (-5875 2200)(-5875 2350);
WIRE 16 -1 (-5875 2150)(-5875 2200);
WIRE 16 -1 (-6075 2200)(-5875 2200);
WIRE 16 -1 (-6075 2150)(-6075 2200);
WIRE 16 -1 (-6325 2200)(-6075 2200);
WIRE 16 -1 (-6725 2200)(-6325 2200);
WIRE 16 -1 (-6325 2150)(-6325 2200);
WIRE 16 -1 (-6250 3375)(-6250 3500);
WIRE 16 -1 (-6250 3500)(-5100 3500);
FORCEPROP 2 LAST SIG_NAME FM_CLK_BUFFER3_EN
J 0
(-5735 3510);
DISPLAY 0.489362 (-5735 3510);
WIRE 16 -1 (-6250 3500)(-6250 3575);
WIRE 16 -1 (-5200 1725)(-4550 1725);
FORCEPROP 2 LAST SIG_NAME SMB_CPU0_3_XLTR_SCL
J 0
(-5185 1735);
DISPLAY 0.489362 (-5185 1735);
WIRE 16 -1 (-5200 1775)(-4550 1775);
FORCEPROP 2 LAST SIG_NAME SMB_CPU0_3_XLTR_SDA
J 0
(-5185 1785);
DISPLAY 0.489362 (-5185 1785);
WIRE 16 -1 (-5200 1625)(-4550 1625);
FORCEPROP 2 LAST SIG_NAME FM_CLK_BUFFER4_EN
J 0
(-5185 1635);
DISPLAY 0.489362 (-5185 1635);
WIRE 16 -1 (-6000 3425)(-5100 3425);
FORCEPROP 2 LAST SIG_NAME FM_CLK_BUFFER4_EN
J 0
(-5735 3435);
DISPLAY 0.489362 (-5735 3435);
WIRE 16 -1 (-6000 3575)(-6000 3425);
WIRE 16 -1 (-6000 3425)(-6000 3375);
WIRE 16 -1 (-5750 5425)(-5750 5575);
WIRE 16 -1 (-5750 5375)(-5750 5425);
WIRE 16 -1 (-5950 5425)(-5750 5425);
WIRE 16 -1 (-5950 5375)(-5950 5425);
WIRE 16 -1 (-6200 5425)(-5950 5425);
WIRE 16 -1 (-6900 5425)(-6200 5425);
WIRE 16 -1 (-6200 5375)(-6200 5425);
WIRE 16 -1 (-5425 4725)(-4775 4725);
FORCEPROP 2 LAST SIG_NAME SMB_CPU0_3_XLTR_SCL
J 0
(-5410 4735);
DISPLAY 0.489362 (-5410 4735);
WIRE 16 -1 (-5425 4775)(-4775 4775);
FORCEPROP 2 LAST SIG_NAME SMB_CPU0_3_XLTR_SDA
J 0
(-5410 4785);
DISPLAY 0.489362 (-5410 4785);
WIRE 16 -1 (-5425 4625)(-4775 4625);
FORCEPROP 2 LAST SIG_NAME FM_CLK_BUFFER3_EN
J 0
(-5410 4635);
DISPLAY 0.489362 (-5410 4635);
WIRE 16 -1 (-3600 2475)(-4100 2475);
WIRE 16 -1 (-4100 2475)(-4100 2675);
WIRE 16 -1 (-4100 2425)(-4100 2475);
WIRE 16 -1 (-3600 2425)(-4100 2425);
WIRE 16 -1 (-4100 2425)(-4100 2375);
WIRE 16 -1 (-3600 2375)(-4100 2375);
WIRE 16 -1 (-4100 2375)(-4100 2325);
WIRE 16 -1 (-3600 2325)(-4100 2325);
WIRE 16 -1 (-4100 2275)(-4100 2325);
WIRE 16 -1 (-3600 2275)(-4100 2275);
WIRE 16 -1 (-3825 4725)(-4575 4725);
FORCEPROP 2 LAST SIG_NAME SMB_CLK_BUF3_SCL
J 0
(-4485 4735);
DISPLAY 0.489362 (-4485 4735);
FORCEPROP 2 LASTPROP $XRERR UNIQUE?
J 0
(-4725 4735);
DISPLAY 0.638298 (-4725 4735);
PAINT MONO (-4725 4735);
DISPLAY INVISIBLE (-4725 4735);
WIRE 16 -1 (-3825 4625)(-4575 4625);
FORCEPROP 2 LAST SIG_NAME FM_CLK_BUFFER3_EN_R
J 0
(-4485 4635);
DISPLAY 0.489362 (-4485 4635);
FORCEPROP 2 LASTPROP $XRERR UNIQUE?
J 0
(-4725 4635);
DISPLAY 0.638298 (-4725 4635);
PAINT MONO (-4725 4635);
DISPLAY INVISIBLE (-4725 4635);
WIRE 16 -1 (-3600 1725)(-4350 1725);
FORCEPROP 2 LAST SIG_NAME SMB_CLK_BUF4_SCL
J 0
(-4260 1735);
DISPLAY 0.489362 (-4260 1735);
FORCEPROP 2 LASTPROP $XRERR UNIQUE?
J 0
(-4500 1735);
DISPLAY 0.638298 (-4500 1735);
PAINT MONO (-4500 1735);
DISPLAY INVISIBLE (-4500 1735);
WIRE 16 -1 (-3600 1625)(-4350 1625);
FORCEPROP 2 LAST SIG_NAME FM_CLK_BUFFER4_EN_R
J 0
(-4260 1635);
DISPLAY 0.489362 (-4260 1635);
FORCEPROP 2 LASTPROP $XRERR UNIQUE?
J 0
(-4500 1635);
DISPLAY 0.638298 (-4500 1635);
PAINT MONO (-4500 1635);
DISPLAY INVISIBLE (-4500 1635);
WIRE 16 -1 (-3600 1775)(-4350 1775);
FORCEPROP 2 LAST SIG_NAME SMB_CLK_BUF4_SDA
J 0
(-4260 1785);
DISPLAY 0.489362 (-4260 1785);
FORCEPROP 2 LASTPROP $XRERR UNIQUE?
J 0
(-4500 1785);
DISPLAY 0.638298 (-4500 1785);
PAINT MONO (-4500 1785);
DISPLAY INVISIBLE (-4500 1785);
WIRE 16 -1 (-3825 4775)(-4575 4775);
FORCEPROP 2 LAST SIG_NAME SMB_CLK_BUF3_SDA
J 0
(-4485 4785);
DISPLAY 0.489362 (-4485 4785);
FORCEPROP 2 LASTPROP $XRERR UNIQUE?
J 0
(-4725 4785);
DISPLAY 0.638298 (-4725 4785);
PAINT MONO (-4725 4785);
DISPLAY INVISIBLE (-4725 4785);
WIRE 16 -1 (-4500 2300)(-4500 2175);
WIRE 16 -1 (-3600 2175)(-4500 2175);
WIRE 16 -1 (-4450 5375)(-4450 5175);
WIRE 16 -1 (-3825 5175)(-4450 5175);
WIRE 16 -1 (-4675 1975)(-3600 1975);
FORCEPROP 2 LAST SIG_NAME CLK_100M_CPU1_CLK11_DN
J 0
(-4510 1985);
DISPLAY 0.489362 (-4510 1985);
WIRE 16 -1 (-4675 2025)(-3600 2025);
FORCEPROP 2 LAST SIG_NAME CLK_100M_CPU1_CLK11_DP
J 0
(-4510 2035);
DISPLAY 0.489362 (-4510 2035);
WIRE 16 -1 (-3825 4875)(-4625 4875);
FORCEPROP 2 LAST SIG_NAME SADR_3
J 0
(-4460 4885);
DISPLAY 0.489362 (-4460 4885);
WIRE 16 -1 (-3600 1875)(-4400 1875);
FORCEPROP 2 LAST SIG_NAME SADR_4
J 0
(-4235 1885);
DISPLAY 0.489362 (-4235 1885);
WIRE 16 -1 (-4625 4975)(-3825 4975);
FORCEPROP 2 LAST SIG_NAME CLK_100M_CPU0_CLK11_DN
J 0
(-4460 4985);
DISPLAY 0.489362 (-4460 4985);
WIRE 16 -1 (-4625 5025)(-3825 5025);
FORCEPROP 2 LAST SIG_NAME CLK_100M_CPU0_CLK11_DP
J 0
(-4460 5035);
DISPLAY 0.489362 (-4460 5035);
WIRE 16 -1 (-2175 1050)(-2175 1225);
WIRE 16 -1 (-2175 1225)(-2350 1225);
WIRE 16 -1 (-2250 2700)(-2250 2475);
WIRE 16 -1 (-2250 2475)(-2350 2475);
WIRE 16 -1 (-2350 2125)(-1525 2125);
FORCEPROP 2 LAST SIG_NAME CLK_100M_E1S_3_R_DP
J 0
(-2260 2135);
DISPLAY 0.489362 (-2260 2135);
FORCEPROP 2 LASTPROP $XRERR UNIQUE?
J 0
(-2500 2135);
DISPLAY 0.638298 (-2500 2135);
PAINT MONO (-2500 2135);
DISPLAY INVISIBLE (-2500 2135);
WIRE 16 -1 (-2350 2075)(-1525 2075);
FORCEPROP 2 LAST SIG_NAME CLK_100M_E1S_3_R_DN
J 0
(-2260 2085);
DISPLAY 0.489362 (-2260 2085);
FORCEPROP 2 LASTPROP $XRERR UNIQUE?
J 0
(-2500 2085);
DISPLAY 0.638298 (-2500 2085);
PAINT MONO (-2500 2085);
DISPLAY INVISIBLE (-2500 2085);
WIRE 16 -1 (-2350 2025)(-1525 2025);
FORCEPROP 2 LAST SIG_NAME CLK_100M_E1S_4_R_DP
J 0
(-2260 2035);
DISPLAY 0.489362 (-2260 2035);
FORCEPROP 2 LASTPROP $XRERR UNIQUE?
J 0
(-2500 2035);
DISPLAY 0.638298 (-2500 2035);
PAINT MONO (-2500 2035);
DISPLAY INVISIBLE (-2500 2035);
WIRE 16 -1 (-2350 1975)(-1525 1975);
FORCEPROP 2 LAST SIG_NAME CLK_100M_E1S_4_R_DN
J 0
(-2260 1985);
DISPLAY 0.489362 (-2260 1985);
FORCEPROP 2 LASTPROP $XRERR UNIQUE?
J 0
(-2500 1985);
DISPLAY 0.638298 (-2500 1985);
PAINT MONO (-2500 1985);
DISPLAY INVISIBLE (-2500 1985);
WIRE 16 -1 (-1625 1250)(-1500 1250);
WIRE 16 -1 (-1625 1525)(-1625 1250);
WIRE 16 -1 (-575 1525)(-1625 1525);
FORCEPROP 0 LAST SIG_NAME CLK_BUF_E1S_4_OE
J 0
(-1010 1535);
DISPLAY 0.489362 (-1010 1535);
WIRE 16 -1 (-2350 1525)(-1625 1525);
WIRE 16 -1 (-1575 1350)(-1500 1350);
WIRE 16 -1 (-1575 1575)(-1575 1350);
WIRE 16 -1 (-575 1575)(-1575 1575);
FORCEPROP 0 LAST SIG_NAME CLK_BUF_E1S_3_OE
J 0
(-1010 1585);
DISPLAY 0.489362 (-1010 1585);
WIRE 16 -1 (-2350 1575)(-1575 1575);
WIRE 16 -1 (-1175 1350)(-1175 1250);
WIRE 16 -1 (-1300 1350)(-1175 1350);
WIRE 16 -1 (-1175 1100)(-1175 1250);
WIRE 16 -1 (-1175 1250)(-1300 1250);
WIRE 16 -1 (-1325 1975)(-525 1975);
FORCEPROP 2 LAST SIG_NAME CLK_100M_E1S_4_DN
J 0
(-1235 1985);
DISPLAY 0.489362 (-1235 1985);
WIRE 16 -1 (-1325 2025)(-525 2025);
FORCEPROP 2 LAST SIG_NAME CLK_100M_E1S_4_DP
J 0
(-1235 2035);
DISPLAY 0.489362 (-1235 2035);
WIRE 16 -1 (-2350 2325)(-2025 2325);
WIRE 16 -1 (-2025 2525)(-2025 2325);
FORCEPROP 2 LAST SIG_NAME CLKBUF4_PLL_MODE
J 0
(-2035 2535);
DISPLAY 0.489362 (-2035 2535);
FORCEPROP 2 LASTPROP $XRERR UNIQUE?
J 0
(-2275 2535);
DISPLAY 0.638298 (-2275 2535);
PAINT MONO (-2275 2535);
DISPLAY INVISIBLE (-2275 2535);
WIRE 16 -1 (-2025 2525)(-1525 2525);
WIRE 16 -1 (-1525 2600)(-1525 2525);
WIRE 16 -1 (-1525 2525)(-1525 2450);
WIRE 16 -1 (-1375 3875)(-1125 3875);
WIRE 16 -1 (-1125 3975)(-1125 3875);
WIRE 16 -1 (-1125 3750)(-1125 3875);
WIRE 16 -1 (-1125 4075)(-1125 3975);
WIRE 16 -1 (-1125 3975)(-1400 3975);
WIRE 16 -1 (-1125 4175)(-1125 4075);
WIRE 16 -1 (-1125 4075)(-1400 4075);
WIRE 16 -1 (-1400 4175)(-1125 4175);
WIRE 16 -1 (-1325 2075)(-525 2075);
FORCEPROP 2 LAST SIG_NAME CLK_100M_E1S_3_DN
J 0
(-1235 2085);
DISPLAY 0.489362 (-1235 2085);
WIRE 16 -1 (-1325 2125)(-525 2125);
FORCEPROP 2 LAST SIG_NAME CLK_100M_E1S_3_DP
J 0
(-1235 2135);
DISPLAY 0.489362 (-1235 2135);
WIRE 16 -1 (-1900 3975)(-1900 4475);
WIRE 16 -1 (-1900 3975)(-1600 3975);
WIRE 16 -1 (-675 4475)(-1900 4475);
FORCEPROP 2 LAST SIG_NAME FM_CLK_100M_M2_1_OE_N
J 0
(-1350 4475);
DISPLAY 0.489362 (-1350 4475);
WIRE 16 -1 (-1900 4475)(-2575 4475);
WIRE 16 -1 (-1850 4075)(-1850 4525);
WIRE 16 -1 (-1850 4075)(-1600 4075);
WIRE 16 -1 (-675 4525)(-1850 4525);
FORCEPROP 0 LAST SIG_NAME CLK_BUF_E1S_2_OE
J 0
(-1350 4535);
DISPLAY 0.489362 (-1350 4535);
WIRE 16 -1 (-2575 4525)(-1850 4525);
WIRE 16 -1 (-1950 4425)(-1950 3875);
WIRE 16 -1 (-675 4425)(-1950 4425);
FORCEPROP 2 LAST SIG_NAME FM_CLK_100M_M2_2_OE_N
J 0
(-1350 4435);
DISPLAY 0.489362 (-1350 4435);
WIRE 16 -1 (-2575 4425)(-1950 4425);
WIRE 16 -1 (-1950 3875)(-1575 3875);
WIRE 16 -1 (-2700 4425)(-2575 4425);
WIRE 16 -1 (-4050 5475)(-4050 5750);
WIRE 16 -1 (-3825 5475)(-4050 5475);
WIRE 16 -1 (-4050 5425)(-4050 5475);
WIRE 16 -1 (-3825 5425)(-4050 5425);
WIRE 16 -1 (-4050 5375)(-4050 5425);
WIRE 16 -1 (-3825 5375)(-4050 5375);
WIRE 16 -1 (-4050 5325)(-4050 5375);
WIRE 16 -1 (-3825 5325)(-4050 5325);
WIRE 16 -1 (-4050 5275)(-4050 5325);
WIRE 16 -1 (-3825 5275)(-4050 5275);
WIRE 16 -1 (-2575 5325)(-2275 5325);
WIRE 16 -1 (-2275 5600)(-2275 5325);
WIRE 16 -1 (-2275 5600)(-1550 5600);
FORCEPROP 2 LAST SIG_NAME CLKBUF3_PLL_MODE
J 0
(-2260 5635);
DISPLAY 0.489362 (-2260 5635);
FORCEPROP 2 LASTPROP $XRERR UNIQUE?
J 0
(-2500 5635);
DISPLAY 0.638298 (-2500 5635);
PAINT MONO (-2500 5635);
DISPLAY INVISIBLE (-2500 5635);
WIRE 16 -1 (-1550 5675)(-1550 5600);
WIRE 16 -1 (-1550 5600)(-1550 5525);
WIRE 16 -1 (-2450 5750)(-2450 5475);
WIRE 16 -1 (-2575 5475)(-2450 5475);
WIRE 16 -1 (-2575 5025)(-1625 5025);
FORCEPROP 2 LAST SIG_NAME CLK_100M_E1S_2_R_DP
J 0
(-2485 5035);
DISPLAY 0.489362 (-2485 5035);
FORCEPROP 2 LASTPROP $XRERR UNIQUE?
J 0
(-2725 5035);
DISPLAY 0.638298 (-2725 5035);
PAINT MONO (-2725 5035);
DISPLAY INVISIBLE (-2725 5035);
WIRE 16 -1 (-2575 4775)(-1625 4775);
FORCEPROP 2 LAST SIG_NAME CLK_100M_M2_2_R_DN
J 0
(-2485 4785);
DISPLAY 0.489362 (-2485 4785);
FORCEPROP 2 LASTPROP $XRERR UNIQUE?
J 0
(-2725 4785);
DISPLAY 0.638298 (-2725 4785);
PAINT MONO (-2725 4785);
DISPLAY INVISIBLE (-2725 4785);
WIRE 16 -1 (-2575 4825)(-1625 4825);
FORCEPROP 2 LAST SIG_NAME CLK_100M_M2_2_R_DP
J 0
(-2485 4835);
DISPLAY 0.489362 (-2485 4835);
FORCEPROP 2 LASTPROP $XRERR UNIQUE?
J 0
(-2725 4835);
DISPLAY 0.638298 (-2725 4835);
PAINT MONO (-2725 4835);
DISPLAY INVISIBLE (-2725 4835);
WIRE 16 -1 (-2575 4875)(-1625 4875);
FORCEPROP 2 LAST SIG_NAME CLK_100M_M2_1_R_DN
J 0
(-2485 4885);
DISPLAY 0.489362 (-2485 4885);
FORCEPROP 2 LASTPROP $XRERR UNIQUE?
J 0
(-2725 4885);
DISPLAY 0.638298 (-2725 4885);
PAINT MONO (-2725 4885);
DISPLAY INVISIBLE (-2725 4885);
WIRE 16 -1 (-2575 4925)(-1625 4925);
FORCEPROP 2 LAST SIG_NAME CLK_100M_M2_1_R_DP
J 0
(-2485 4935);
DISPLAY 0.489362 (-2485 4935);
FORCEPROP 2 LASTPROP $XRERR UNIQUE?
J 0
(-2725 4935);
DISPLAY 0.638298 (-2725 4935);
PAINT MONO (-2725 4935);
DISPLAY INVISIBLE (-2725 4935);
WIRE 16 -1 (-2575 4975)(-1625 4975);
FORCEPROP 2 LAST SIG_NAME CLK_100M_E1S_2_R_DN
J 0
(-2485 4985);
DISPLAY 0.489362 (-2485 4985);
FORCEPROP 2 LASTPROP $XRERR UNIQUE?
J 0
(-2725 4985);
DISPLAY 0.638298 (-2725 4985);
PAINT MONO (-2725 4985);
DISPLAY INVISIBLE (-2725 4985);
WIRE 16 -1 (-2575 5075)(-1625 5075);
FORCEPROP 2 LAST SIG_NAME CLK_100M_E1S_1_R_DN
J 0
(-2485 5085);
DISPLAY 0.489362 (-2485 5085);
FORCEPROP 2 LASTPROP $XRERR UNIQUE?
J 0
(-2725 5085);
DISPLAY 0.638298 (-2725 5085);
PAINT MONO (-2725 5085);
DISPLAY INVISIBLE (-2725 5085);
WIRE 16 -1 (-2575 5125)(-1625 5125);
FORCEPROP 2 LAST SIG_NAME CLK_100M_E1S_1_R_DP
J 0
(-2485 5135);
DISPLAY 0.489362 (-2485 5135);
FORCEPROP 2 LASTPROP $XRERR UNIQUE?
J 0
(-2725 5135);
DISPLAY 0.638298 (-2725 5135);
PAINT MONO (-2725 5135);
DISPLAY INVISIBLE (-2725 5135);
WIRE 16 -1 (-1800 4175)(-1600 4175);
WIRE 16 -1 (-1800 4175)(-1800 4575);
WIRE 16 -1 (-675 4575)(-1800 4575);
FORCEPROP 0 LAST SIG_NAME CLK_BUF_E1S_1_OE
J 0
(-1350 4585);
DISPLAY 0.489362 (-1350 4585);
WIRE 16 -1 (-2575 4575)(-1800 4575);
WIRE 16 -1 (-1425 4875)(-675 4875);
FORCEPROP 2 LAST SIG_NAME CLK_100M_M2_1_DN
J 0
(-1335 4885);
DISPLAY 0.489362 (-1335 4885);
WIRE 16 -1 (-1425 5125)(-675 5125);
FORCEPROP 2 LAST SIG_NAME CLK_100M_E1S_1_DP
J 0
(-1335 5135);
DISPLAY 0.489362 (-1335 5135);
WIRE 16 -1 (-1425 5025)(-675 5025);
FORCEPROP 2 LAST SIG_NAME CLK_100M_E1S_2_DP
J 0
(-1335 5035);
DISPLAY 0.489362 (-1335 5035);
WIRE 16 -1 (-1425 5075)(-675 5075);
FORCEPROP 2 LAST SIG_NAME CLK_100M_E1S_1_DN
J 0
(-1335 5085);
DISPLAY 0.489362 (-1335 5085);
WIRE 16 -1 (-1425 4975)(-675 4975);
FORCEPROP 2 LAST SIG_NAME CLK_100M_E1S_2_DN
J 0
(-1335 4985);
DISPLAY 0.489362 (-1335 4985);
WIRE 16 -1 (-1425 4925)(-675 4925);
FORCEPROP 2 LAST SIG_NAME CLK_100M_M2_1_DP
J 0
(-1335 4935);
DISPLAY 0.489362 (-1335 4935);
WIRE 16 -1 (-1425 4825)(-675 4825);
FORCEPROP 2 LAST SIG_NAME CLK_100M_M2_2_DP
J 0
(-1335 4835);
DISPLAY 0.489362 (-1335 4835);
WIRE 16 -1 (-1425 4775)(-675 4775);
FORCEPROP 2 LAST SIG_NAME CLK_100M_M2_2_DN
J 0
(-1350 4785);
DISPLAY 0.489362 (-1350 4785);
DOT 1 (-6250 3850);
DOT 1 (-4100 2325);
DOT 1 (-7675 1700);
DOT 1 (-8325 2200);
DOT 1 (-8500 5425);
DOT 1 (-5950 5425);
DOT 1 (-4100 2475);
DOT 1 (-6000 3425);
DOT 1 (-6250 3500);
DOT 1 (-6250 3125);
DOT 1 (-1175 1250);
DOT 1 (-8275 3450);
DOT 1 (-8525 3525);
DOT 1 (-4100 2375);
DOT 1 (-4100 2425);
DOT 1 (-5750 5425);
DOT 1 (-6200 5425);
DOT 1 (-7395 4925);
DOT 1 (-7625 4925);
DOT 1 (-7850 4925);
DOT 1 (-8100 4925);
DOT 1 (-8500 4925);
DOT 1 (-7220 1700);
DOT 1 (-7450 1700);
DOT 1 (-8325 1700);
DOT 1 (-4050 5375);
DOT 1 (-4050 5325);
DOT 1 (-4050 5475);
DOT 1 (-4050 5425);
DOT 1 (-7350 5425);
DOT 1 (-7175 2200);
DOT 1 (-6325 2200);
DOT 1 (-6075 2200);
DOT 1 (-5875 2200);
DOT 1 (-1800 4575);
DOT 1 (-1125 4075);
DOT 1 (-1125 3975);
DOT 1 (-1125 3875);
DOT 1 (-1950 4425);
DOT 1 (-1900 4475);
DOT 1 (-7925 1700);
DOT 1 (-1550 5600);
DOT 1 (-1525 2525);
DOT 1 (-1625 1525);
DOT 1 (-1575 1575);
DOT 1 (-1850 4525);
FORCENOTE
TO E1.S#3
(-975 950) 0;
DISPLAY LEFT (-975 950);
DISPLAY 1.595745 (-975 950);
FORCENOTE
TO E1.S#4
(-975 800) 0;
DISPLAY LEFT (-975 800);
DISPLAY 1.595745 (-975 800);
FORCENOTE
TO M.2#1
(-800 3825) 0;
DISPLAY LEFT (-800 3825);
DISPLAY 1.595745 (-800 3825);
FORCENOTE
TO E1.S#2
(-825 4025) 0;
DISPLAY LEFT (-825 4025);
DISPLAY 1.595745 (-825 4025);
FORCENOTE
TO E1.S#1
(-825 4200) 0;
DISPLAY LEFT (-825 4200);
DISPLAY 1.595745 (-825 4200);
FORCENOTE
TO M.2#2
(-800 3625) 0;
DISPLAY LEFT (-800 3625);
DISPLAY 1.595745 (-800 3625);
QUIT
